G04 ================== begin FILE IDENTIFICATION RECORD ==================*
G04 Layout Name:  D:/<user>/Wistron_project/16315-1/gbr/16315-1.brd*
G04 Film Name:    SE_REF_L8*
G04 File Format:  Gerber RS274X*
G04 File Origin:  Cadence Allegro 16.5-S056*
G04 Origin Date:  Fri Jun 09 15:32:58 2017*
G04 *
G04 Layer:  BOARD GEOMETRY/SE_REF_L8_TBL*
G04 Layer:  BOARD GEOMETRY/SE_REF_L8_L8*
G04 Layer:  BOARD GEOMETRY/PANEL_OUTLINE*
G04 *
G04 Offset:    (0.00 0.00)*
G04 Mirror:    No*
G04 Mode:      Positive*
G04 Rotation:  0*
G04 FullContactRelief:  No*
G04 UndefLineWidth:     6.00*
G04 ================== end FILE IDENTIFICATION RECORD ====================*
%FSLAX35Y35*MOIN*%
%IR0*IPPOS*OFA0.00000B0.00000*MIA0B0*SFA1.00000B1.00000*%
%ADD10C,.02*%
%ADD11C,.006*%
%ADD12C,.00475*%
G75*
%LPD*%
G75*
G54D10*
G01X1985143Y1554618D02*
X2720143D01*
G01X1985143Y1623918D02*
Y1554618D01*
G01Y1589268D02*
X2720143D01*
G01X1985143Y1623918D02*
X2720143D01*
G01X2160143D02*
Y1554618D01*
G01X2405143Y1623918D02*
Y1554618D01*
G01X2510143Y1623918D02*
Y1554618D01*
G01X2720143Y1623918D02*
Y1554618D01*
G54D11*
G01X6250Y-185556D02*
Y-203056D01*
G01X1228Y-185556D02*
X11272D01*
G01X20038Y-203056D02*
Y-185556D01*
G01Y-194014D02*
X21130Y-192556D01*
X22222Y-191681D01*
X23968Y-191390D01*
X25278Y-191681D01*
X26807Y-192848D01*
X27462Y-194598D01*
Y-203056D01*
G01X41250Y-191390D02*
Y-203056D01*
G01Y-186723D02*
X40813Y-186431D01*
Y-185848D01*
X41250Y-185556D01*
X41687Y-185848D01*
Y-186431D01*
X41250Y-186723D01*
G01X55475Y-201015D02*
X56567Y-202181D01*
X58095Y-203056D01*
X59405D01*
X60715Y-202473D01*
X61588Y-201598D01*
X62025Y-200432D01*
X61807Y-198681D01*
X60933Y-197806D01*
X57003Y-196056D01*
X56130Y-194014D01*
X56567Y-192556D01*
X57440Y-191681D01*
X58750Y-191390D01*
X60060Y-191681D01*
X61370Y-192556D01*
G01X90693Y-207431D02*
X92222Y-208598D01*
X93968Y-208889D01*
X95496Y-208598D01*
X96807Y-207140D01*
X97680Y-205098D01*
Y-191390D01*
G01Y-193723D02*
X96807Y-192556D01*
X95496Y-191681D01*
X93968Y-191390D01*
X92222Y-191973D01*
X91130Y-193139D01*
X90256Y-195181D01*
X89820Y-197223D01*
X90038Y-198973D01*
X90912Y-201015D01*
X92222Y-202473D01*
X93968Y-203056D01*
X95278Y-202764D01*
X96807Y-201598D01*
X97680Y-200432D01*
G01X107975Y-195181D02*
X114962D01*
X114307Y-193139D01*
X113215Y-191973D01*
X111687Y-191390D01*
X110158Y-191681D01*
X108848Y-192556D01*
X107975Y-194598D01*
X107538Y-196348D01*
Y-198098D01*
X107975Y-199848D01*
X109067Y-201598D01*
X110377Y-202764D01*
X111905Y-203056D01*
X113433Y-202473D01*
X114962Y-200723D01*
G01X125693Y-203056D02*
Y-191390D01*
G01Y-193723D02*
X126785Y-192556D01*
X127877Y-191681D01*
X129405Y-191390D01*
X130496Y-191681D01*
X131807Y-192556D01*
G01X142320Y-203056D02*
Y-185556D01*
G01Y-194306D02*
X143412Y-192556D01*
X144722Y-191681D01*
X146032Y-191390D01*
X147996Y-191973D01*
X149307Y-193139D01*
X150180Y-195181D01*
Y-197514D01*
X149743Y-199848D01*
X148870Y-201598D01*
X147342Y-202764D01*
X146032Y-203056D01*
X144722Y-202764D01*
X143412Y-201890D01*
X142320Y-200432D01*
G01X160475Y-195181D02*
X167462D01*
X166807Y-193139D01*
X165715Y-191973D01*
X164187Y-191390D01*
X162658Y-191681D01*
X161348Y-192556D01*
X160475Y-194598D01*
X160038Y-196348D01*
Y-198098D01*
X160475Y-199848D01*
X161567Y-201598D01*
X162877Y-202764D01*
X164405Y-203056D01*
X165933Y-202473D01*
X167462Y-200723D01*
G01X178193Y-203056D02*
Y-191390D01*
G01Y-193723D02*
X179285Y-192556D01*
X180377Y-191681D01*
X181905Y-191390D01*
X182996Y-191681D01*
X184307Y-192556D01*
G01X216250Y-191390D02*
Y-203056D01*
G01Y-186723D02*
X215813Y-186431D01*
Y-185848D01*
X216250Y-185556D01*
X216687Y-185848D01*
Y-186431D01*
X216250Y-186723D01*
G01X230475Y-201015D02*
X231567Y-202181D01*
X233095Y-203056D01*
X234405D01*
X235715Y-202473D01*
X236588Y-201598D01*
X237025Y-200432D01*
X236807Y-198681D01*
X235933Y-197806D01*
X232003Y-196056D01*
X231130Y-194014D01*
X231567Y-192556D01*
X232440Y-191681D01*
X233750Y-191390D01*
X235060Y-191681D01*
X236370Y-192556D01*
G01X265256Y-207431D02*
X266785Y-208598D01*
X268095Y-208889D01*
X269842Y-208306D01*
X271152Y-206848D01*
X271807Y-204222D01*
Y-191390D01*
G01Y-186723D02*
X271370Y-186431D01*
Y-185848D01*
X271807Y-185556D01*
X272243Y-185848D01*
Y-186431D01*
X271807Y-186723D01*
G01X282538Y-191390D02*
Y-199556D01*
X283412Y-201598D01*
X284722Y-202764D01*
X286250Y-203056D01*
X287778Y-202764D01*
X289088Y-201598D01*
X289962Y-199556D01*
G01Y-203056D02*
Y-191390D01*
G01X300475Y-201015D02*
X301567Y-202181D01*
X303095Y-203056D01*
X304405D01*
X305715Y-202473D01*
X306588Y-201598D01*
X307025Y-200432D01*
X306807Y-198681D01*
X305933Y-197806D01*
X302003Y-196056D01*
X301130Y-194014D01*
X301567Y-192556D01*
X302440Y-191681D01*
X303750Y-191390D01*
X305060Y-191681D01*
X306370Y-192556D01*
G01X321250Y-185556D02*
Y-203056D01*
G01X318193Y-191390D02*
X324307D01*
G01X354940Y-203056D02*
Y-188181D01*
X355377Y-186723D01*
X356250Y-185848D01*
X357560Y-185556D01*
X358870Y-186139D01*
X359525Y-187598D01*
G01X356905Y-192556D02*
X352538D01*
G01X373750Y-203056D02*
X372440Y-202764D01*
X371130Y-201598D01*
X370256Y-199556D01*
X369820Y-197223D01*
X370256Y-194889D01*
X371130Y-192848D01*
X372440Y-191681D01*
X373750Y-191390D01*
X375060Y-191681D01*
X376370Y-192848D01*
X377243Y-194889D01*
X377462Y-197223D01*
X377243Y-199556D01*
X376370Y-201598D01*
X375060Y-202764D01*
X373750Y-203056D01*
G01X388193D02*
Y-191390D01*
G01Y-193723D02*
X389285Y-192556D01*
X390377Y-191681D01*
X391905Y-191390D01*
X392996Y-191681D01*
X394307Y-192556D01*
G01X421665Y-208306D02*
X422975Y-208889D01*
X424722Y-208306D01*
X425813Y-207140D01*
X426687Y-205681D01*
X427996Y-201015D01*
X430835Y-191390D01*
G01X423848D02*
X427996Y-201015D01*
G01X443750Y-203056D02*
X442440Y-202764D01*
X441130Y-201598D01*
X440256Y-199556D01*
X439820Y-197223D01*
X440256Y-194889D01*
X441130Y-192848D01*
X442440Y-191681D01*
X443750Y-191390D01*
X445060Y-191681D01*
X446370Y-192848D01*
X447243Y-194889D01*
X447462Y-197223D01*
X447243Y-199556D01*
X446370Y-201598D01*
X445060Y-202764D01*
X443750Y-203056D01*
G01X457538Y-191390D02*
Y-199556D01*
X458412Y-201598D01*
X459722Y-202764D01*
X461250Y-203056D01*
X462778Y-202764D01*
X464088Y-201598D01*
X464962Y-199556D01*
G01Y-203056D02*
Y-191390D01*
G01X475693Y-203056D02*
Y-191390D01*
G01Y-193723D02*
X476785Y-192556D01*
X477877Y-191681D01*
X479405Y-191390D01*
X480496Y-191681D01*
X481807Y-192556D01*
G01X510693Y-203056D02*
Y-191390D01*
G01Y-193723D02*
X511785Y-192556D01*
X512877Y-191681D01*
X514405Y-191390D01*
X515496Y-191681D01*
X516807Y-192556D01*
G01X527975Y-195181D02*
X534962D01*
X534307Y-193139D01*
X533215Y-191973D01*
X531687Y-191390D01*
X530158Y-191681D01*
X528848Y-192556D01*
X527975Y-194598D01*
X527538Y-196348D01*
Y-198098D01*
X527975Y-199848D01*
X529067Y-201598D01*
X530377Y-202764D01*
X531905Y-203056D01*
X533433Y-202473D01*
X534962Y-200723D01*
G01X547440Y-203056D02*
Y-188181D01*
X547877Y-186723D01*
X548750Y-185848D01*
X550060Y-185556D01*
X551370Y-186139D01*
X552025Y-187598D01*
G01X549405Y-192556D02*
X545038D01*
G01X562975Y-195181D02*
X569962D01*
X569307Y-193139D01*
X568215Y-191973D01*
X566687Y-191390D01*
X565158Y-191681D01*
X563848Y-192556D01*
X562975Y-194598D01*
X562538Y-196348D01*
Y-198098D01*
X562975Y-199848D01*
X564067Y-201598D01*
X565377Y-202764D01*
X566905Y-203056D01*
X568433Y-202473D01*
X569962Y-200723D01*
G01X580693Y-203056D02*
Y-191390D01*
G01Y-193723D02*
X581785Y-192556D01*
X582877Y-191681D01*
X584405Y-191390D01*
X585496Y-191681D01*
X586807Y-192556D01*
G01X597975Y-195181D02*
X604962D01*
X604307Y-193139D01*
X603215Y-191973D01*
X601687Y-191390D01*
X600158Y-191681D01*
X598848Y-192556D01*
X597975Y-194598D01*
X597538Y-196348D01*
Y-198098D01*
X597975Y-199848D01*
X599067Y-201598D01*
X600377Y-202764D01*
X601905Y-203056D01*
X603433Y-202473D01*
X604962Y-200723D01*
G01X615038Y-203056D02*
Y-191390D01*
G01Y-194306D02*
X615912Y-192848D01*
X617222Y-191681D01*
X618968Y-191390D01*
X620496Y-191681D01*
X621807Y-192848D01*
X622462Y-194889D01*
Y-203056D01*
G01X639743Y-192848D02*
X638215Y-191681D01*
X636905Y-191390D01*
X635158Y-191973D01*
X633848Y-193139D01*
X632975Y-195181D01*
X632756Y-197223D01*
X632975Y-199265D01*
X633848Y-201015D01*
X635158Y-202473D01*
X636905Y-203056D01*
X638433Y-202473D01*
X639743Y-201306D01*
G01X650475Y-195181D02*
X657462D01*
X656807Y-193139D01*
X655715Y-191973D01*
X654187Y-191390D01*
X652658Y-191681D01*
X651348Y-192556D01*
X650475Y-194598D01*
X650038Y-196348D01*
Y-198098D01*
X650475Y-199848D01*
X651567Y-201598D01*
X652877Y-202764D01*
X654405Y-203056D01*
X655933Y-202473D01*
X657462Y-200723D01*
G01X688750Y-185556D02*
Y-203056D01*
G01X685693Y-191390D02*
X691807D01*
G01X706250Y-203056D02*
X704940Y-202764D01*
X703630Y-201598D01*
X702756Y-199556D01*
X702320Y-197223D01*
X702756Y-194889D01*
X703630Y-192848D01*
X704940Y-191681D01*
X706250Y-191390D01*
X707560Y-191681D01*
X708870Y-192848D01*
X709743Y-194889D01*
X709962Y-197223D01*
X709743Y-199556D01*
X708870Y-201598D01*
X707560Y-202764D01*
X706250Y-203056D01*
G01X739940D02*
Y-188181D01*
X740377Y-186723D01*
X741250Y-185848D01*
X742560Y-185556D01*
X743870Y-186139D01*
X744525Y-187598D01*
G01X741905Y-192556D02*
X737538D01*
G01X758750Y-191390D02*
Y-203056D01*
G01Y-186723D02*
X758313Y-186431D01*
Y-185848D01*
X758750Y-185556D01*
X759187Y-185848D01*
Y-186431D01*
X758750Y-186723D01*
G01X772538Y-203056D02*
Y-191390D01*
G01Y-194306D02*
X773412Y-192848D01*
X774722Y-191681D01*
X776468Y-191390D01*
X777996Y-191681D01*
X779307Y-192848D01*
X779962Y-194889D01*
Y-203056D01*
G01X797680Y-185556D02*
Y-203056D01*
G01Y-200432D02*
X796807Y-201890D01*
X795496Y-202764D01*
X793968Y-203056D01*
X792222Y-202473D01*
X790912Y-201015D01*
X790038Y-199265D01*
X789820Y-197223D01*
X790038Y-195181D01*
X790912Y-193431D01*
X792222Y-191973D01*
X793968Y-191390D01*
X795496Y-191681D01*
X796588Y-192265D01*
X797680Y-193431D01*
G01X828750Y-185556D02*
Y-203056D01*
G01X825693Y-191390D02*
X831807D01*
G01X842538Y-203056D02*
Y-185556D01*
G01Y-194014D02*
X843630Y-192556D01*
X844722Y-191681D01*
X846468Y-191390D01*
X847778Y-191681D01*
X849307Y-192848D01*
X849962Y-194598D01*
Y-203056D01*
G01X860475Y-195181D02*
X867462D01*
X866807Y-193139D01*
X865715Y-191973D01*
X864187Y-191390D01*
X862658Y-191681D01*
X861348Y-192556D01*
X860475Y-194598D01*
X860038Y-196348D01*
Y-198098D01*
X860475Y-199848D01*
X861567Y-201598D01*
X862877Y-202764D01*
X864405Y-203056D01*
X865933Y-202473D01*
X867462Y-200723D01*
G01X894165D02*
X895912Y-202181D01*
X897877Y-203056D01*
X899623D01*
X901370Y-202181D01*
X902680Y-200723D01*
X903335Y-198681D01*
X902898Y-196640D01*
X901807Y-194889D01*
X899842Y-193723D01*
X897222Y-193139D01*
X895693Y-191973D01*
X895038Y-189931D01*
X895475Y-187889D01*
X896567Y-186431D01*
X898095Y-185556D01*
X899623D01*
X901152Y-186139D01*
X902462Y-187598D01*
G01X920617Y-203056D02*
X911883D01*
Y-185556D01*
X920617D01*
G01X917123Y-194014D02*
X911883D01*
G01X951250Y-191390D02*
Y-203056D01*
G01Y-186723D02*
X950813Y-186431D01*
Y-185848D01*
X951250Y-185556D01*
X951687Y-185848D01*
Y-186431D01*
X951250Y-186723D01*
G01X962200Y-203056D02*
Y-191390D01*
G01Y-194598D02*
X962855Y-193139D01*
X963947Y-191973D01*
X965475Y-191390D01*
X967003Y-191973D01*
X968095Y-193139D01*
X968750Y-194598D01*
Y-203056D01*
G01Y-194598D02*
X969405Y-193139D01*
X970496Y-191973D01*
X972025Y-191390D01*
X973553Y-191973D01*
X974645Y-193139D01*
X975300Y-194889D01*
Y-203056D01*
G01X982320Y-208889D02*
Y-191390D01*
G01Y-194014D02*
X983412Y-192556D01*
X984503Y-191681D01*
X986250Y-191390D01*
X987778Y-191681D01*
X989307Y-193139D01*
X989962Y-195181D01*
X990180Y-197223D01*
X989962Y-199265D01*
X989307Y-201306D01*
X987996Y-202473D01*
X986250Y-203056D01*
X984722Y-202764D01*
X983193Y-201890D01*
X982320Y-200723D01*
G01X1000475Y-195181D02*
X1007462D01*
X1006807Y-193139D01*
X1005715Y-191973D01*
X1004187Y-191390D01*
X1002658Y-191681D01*
X1001348Y-192556D01*
X1000475Y-194598D01*
X1000038Y-196348D01*
Y-198098D01*
X1000475Y-199848D01*
X1001567Y-201598D01*
X1002877Y-202764D01*
X1004405Y-203056D01*
X1005933Y-202473D01*
X1007462Y-200723D01*
G01X1025180Y-185556D02*
Y-203056D01*
G01Y-200432D02*
X1024307Y-201890D01*
X1022996Y-202764D01*
X1021468Y-203056D01*
X1019722Y-202473D01*
X1018412Y-201015D01*
X1017538Y-199265D01*
X1017320Y-197223D01*
X1017538Y-195181D01*
X1018412Y-193431D01*
X1019722Y-191973D01*
X1021468Y-191390D01*
X1022996Y-191681D01*
X1024088Y-192265D01*
X1025180Y-193431D01*
G01X1042680Y-203056D02*
Y-191390D01*
G01Y-193431D02*
X1041807Y-192265D01*
X1040496Y-191681D01*
X1038968Y-191390D01*
X1037440Y-191973D01*
X1036130Y-193139D01*
X1035256Y-194889D01*
X1034820Y-197223D01*
X1035256Y-199556D01*
X1036130Y-201306D01*
X1037440Y-202473D01*
X1038968Y-203056D01*
X1040496Y-202764D01*
X1041807Y-201890D01*
X1042680Y-200723D01*
G01X1052538Y-203056D02*
Y-191390D01*
G01Y-194306D02*
X1053412Y-192848D01*
X1054722Y-191681D01*
X1056468Y-191390D01*
X1057996Y-191681D01*
X1059307Y-192848D01*
X1059962Y-194889D01*
Y-203056D01*
G01X1077243Y-192848D02*
X1075715Y-191681D01*
X1074405Y-191390D01*
X1072658Y-191973D01*
X1071348Y-193139D01*
X1070475Y-195181D01*
X1070256Y-197223D01*
X1070475Y-199265D01*
X1071348Y-201015D01*
X1072658Y-202473D01*
X1074405Y-203056D01*
X1075933Y-202473D01*
X1077243Y-201306D01*
G01X1087975Y-195181D02*
X1094962D01*
X1094307Y-193139D01*
X1093215Y-191973D01*
X1091687Y-191390D01*
X1090158Y-191681D01*
X1088848Y-192556D01*
X1087975Y-194598D01*
X1087538Y-196348D01*
Y-198098D01*
X1087975Y-199848D01*
X1089067Y-201598D01*
X1090377Y-202764D01*
X1091905Y-203056D01*
X1093433Y-202473D01*
X1094962Y-200723D01*
G01X1126250Y-185556D02*
Y-203056D01*
G01X1123193Y-191390D02*
X1129307D01*
G01X1140693Y-203056D02*
Y-191390D01*
G01Y-193723D02*
X1141785Y-192556D01*
X1142877Y-191681D01*
X1144405Y-191390D01*
X1145496Y-191681D01*
X1146807Y-192556D01*
G01X1165180Y-203056D02*
Y-191390D01*
G01Y-193431D02*
X1164307Y-192265D01*
X1162996Y-191681D01*
X1161468Y-191390D01*
X1159940Y-191973D01*
X1158630Y-193139D01*
X1157756Y-194889D01*
X1157320Y-197223D01*
X1157756Y-199556D01*
X1158630Y-201306D01*
X1159940Y-202473D01*
X1161468Y-203056D01*
X1162996Y-202764D01*
X1164307Y-201890D01*
X1165180Y-200723D01*
G01X1182243Y-192848D02*
X1180715Y-191681D01*
X1179405Y-191390D01*
X1177658Y-191973D01*
X1176348Y-193139D01*
X1175475Y-195181D01*
X1175256Y-197223D01*
X1175475Y-199265D01*
X1176348Y-201015D01*
X1177658Y-202473D01*
X1179405Y-203056D01*
X1180933Y-202473D01*
X1182243Y-201306D01*
G01X1192975Y-195181D02*
X1199962D01*
X1199307Y-193139D01*
X1198215Y-191973D01*
X1196687Y-191390D01*
X1195158Y-191681D01*
X1193848Y-192556D01*
X1192975Y-194598D01*
X1192538Y-196348D01*
Y-198098D01*
X1192975Y-199848D01*
X1194067Y-201598D01*
X1195377Y-202764D01*
X1196905Y-203056D01*
X1198433Y-202473D01*
X1199962Y-200723D01*
G01X1210475Y-201015D02*
X1211567Y-202181D01*
X1213095Y-203056D01*
X1214405D01*
X1215715Y-202473D01*
X1216588Y-201598D01*
X1217025Y-200432D01*
X1216807Y-198681D01*
X1215933Y-197806D01*
X1212003Y-196056D01*
X1211130Y-194014D01*
X1211567Y-192556D01*
X1212440Y-191681D01*
X1213750Y-191390D01*
X1215060Y-191681D01*
X1216370Y-192556D01*
G01X1248750Y-191390D02*
Y-203056D01*
G01Y-186723D02*
X1248313Y-186431D01*
Y-185848D01*
X1248750Y-185556D01*
X1249187Y-185848D01*
Y-186431D01*
X1248750Y-186723D01*
G01X1262538Y-203056D02*
Y-191390D01*
G01Y-194306D02*
X1263412Y-192848D01*
X1264722Y-191681D01*
X1266468Y-191390D01*
X1267996Y-191681D01*
X1269307Y-192848D01*
X1269962Y-194889D01*
Y-203056D01*
G01X1301250D02*
Y-185556D01*
G01X1322680Y-203056D02*
Y-191390D01*
G01Y-193431D02*
X1321807Y-192265D01*
X1320496Y-191681D01*
X1318968Y-191390D01*
X1317440Y-191973D01*
X1316130Y-193139D01*
X1315256Y-194889D01*
X1314820Y-197223D01*
X1315256Y-199556D01*
X1316130Y-201306D01*
X1317440Y-202473D01*
X1318968Y-203056D01*
X1320496Y-202764D01*
X1321807Y-201890D01*
X1322680Y-200723D01*
G01X1331665Y-208306D02*
X1332975Y-208889D01*
X1334722Y-208306D01*
X1335813Y-207140D01*
X1336687Y-205681D01*
X1337996Y-201015D01*
X1340835Y-191390D01*
G01X1333848D02*
X1337996Y-201015D01*
G01X1350475Y-195181D02*
X1357462D01*
X1356807Y-193139D01*
X1355715Y-191973D01*
X1354187Y-191390D01*
X1352658Y-191681D01*
X1351348Y-192556D01*
X1350475Y-194598D01*
X1350038Y-196348D01*
Y-198098D01*
X1350475Y-199848D01*
X1351567Y-201598D01*
X1352877Y-202764D01*
X1354405Y-203056D01*
X1355933Y-202473D01*
X1357462Y-200723D01*
G01X1368193Y-203056D02*
Y-191390D01*
G01Y-193723D02*
X1369285Y-192556D01*
X1370377Y-191681D01*
X1371905Y-191390D01*
X1372996Y-191681D01*
X1374307Y-192556D01*
G01X1401883Y-185556D02*
Y-203056D01*
X1410617D01*
G01X1423750D02*
X1425278Y-202764D01*
X1427025Y-201890D01*
X1428117Y-200432D01*
X1428553Y-198389D01*
X1428117Y-196348D01*
X1426807Y-194598D01*
X1424842Y-193723D01*
X1422658D01*
X1421348Y-193139D01*
X1420256Y-191681D01*
X1419820Y-189640D01*
X1420475Y-187598D01*
X1422003Y-186139D01*
X1423750Y-185556D01*
X1425496Y-186139D01*
X1427025Y-187598D01*
X1427680Y-189640D01*
X1427243Y-191681D01*
X1426152Y-193139D01*
X1424842Y-193723D01*
X1422658D01*
X1420693Y-194598D01*
X1419383Y-196348D01*
X1418947Y-198389D01*
X1419383Y-200432D01*
X1420475Y-201890D01*
X1422222Y-202764D01*
X1423750Y-203056D01*
G01X1441250Y-203639D02*
X1440813Y-203348D01*
Y-202764D01*
X1441250Y-202473D01*
X1441687Y-202764D01*
Y-203348D01*
X1441250Y-203639D01*
G01X2008773Y1616518D02*
X2014013D01*
G01X2011393D02*
Y1599018D01*
G01X2008773D02*
X2014013D01*
G01X2023216D02*
Y1616518D01*
X2028893Y1601935D01*
X2034570Y1616518D01*
Y1599018D01*
G01X2042026D02*
Y1616518D01*
X2047266D01*
X2049013Y1615643D01*
X2050323Y1613601D01*
X2050760Y1611268D01*
X2050323Y1608935D01*
X2049231Y1607185D01*
X2047266Y1606309D01*
X2042026D01*
G01X2062801Y1593185D02*
X2060618Y1596101D01*
X2059526Y1599018D01*
Y1610684D01*
X2060618Y1613601D01*
X2062801Y1616518D01*
G01X2081393Y1599018D02*
X2079646Y1599310D01*
X2078118Y1600476D01*
X2076808Y1602226D01*
X2075934Y1604268D01*
X2075498Y1606601D01*
Y1608935D01*
X2075934Y1611268D01*
X2076808Y1613310D01*
X2078118Y1615059D01*
X2079646Y1616226D01*
X2081393Y1616518D01*
X2083139Y1616226D01*
X2084668Y1615059D01*
X2085978Y1613310D01*
X2086852Y1611268D01*
X2087288Y1608935D01*
Y1606601D01*
X2086852Y1604268D01*
X2085978Y1602226D01*
X2084668Y1600476D01*
X2083139Y1599310D01*
X2081393Y1599018D01*
G01X2095181D02*
Y1616518D01*
G01Y1608060D02*
X2096273Y1609518D01*
X2097365Y1610393D01*
X2099111Y1610684D01*
X2100421Y1610393D01*
X2101950Y1609226D01*
X2102605Y1607476D01*
Y1599018D01*
G01X2109843D02*
Y1610684D01*
G01Y1607476D02*
X2110498Y1608935D01*
X2111590Y1610101D01*
X2113118Y1610684D01*
X2114646Y1610101D01*
X2115738Y1608935D01*
X2116393Y1607476D01*
Y1599018D01*
G01Y1607476D02*
X2117048Y1608935D01*
X2118139Y1610101D01*
X2119668Y1610684D01*
X2121196Y1610101D01*
X2122288Y1608935D01*
X2122943Y1607185D01*
Y1599018D01*
G01X2134985Y1593185D02*
X2137168Y1596101D01*
X2138260Y1599018D01*
Y1610684D01*
X2137168Y1613601D01*
X2134985Y1616518D01*
G01X1987108Y1636001D02*
X1988855Y1634543D01*
X1990820Y1633668D01*
X1992566D01*
X1994313Y1634543D01*
X1995623Y1636001D01*
X1996278Y1638043D01*
X1995841Y1640084D01*
X1994750Y1641835D01*
X1992785Y1643001D01*
X1990165Y1643585D01*
X1988636Y1644751D01*
X1987981Y1646793D01*
X1988418Y1648835D01*
X1989510Y1650293D01*
X1991038Y1651168D01*
X1992566D01*
X1994095Y1650585D01*
X1995405Y1649126D01*
G01X2013560Y1633668D02*
X2004826D01*
Y1651168D01*
X2013560D01*
G01X2010066Y1642710D02*
X2004826D01*
G01X2041573Y1651168D02*
X2046813D01*
G01X2044193D02*
Y1633668D01*
G01X2041573D02*
X2046813D01*
G01X2056016D02*
Y1651168D01*
X2061693Y1636585D01*
X2067370Y1651168D01*
Y1633668D01*
G01X2074826D02*
Y1651168D01*
X2080066D01*
X2081813Y1650293D01*
X2083123Y1648251D01*
X2083560Y1645918D01*
X2083123Y1643585D01*
X2082031Y1641835D01*
X2080066Y1640959D01*
X2074826D01*
G01X2101060Y1633668D02*
X2092326D01*
Y1651168D01*
X2101060D01*
G01X2097566Y1642710D02*
X2092326D01*
G01X2109390Y1633668D02*
Y1651168D01*
X2113756D01*
X2115503Y1650293D01*
X2116813Y1649126D01*
X2117905Y1647377D01*
X2118778Y1645334D01*
X2118996Y1642418D01*
X2118778Y1639501D01*
X2117905Y1637459D01*
X2116813Y1635709D01*
X2115503Y1634543D01*
X2113756Y1633668D01*
X2109390D01*
G01X2126234D02*
X2131693Y1651168D01*
X2137152Y1633668D01*
G01X2135186Y1639793D02*
X2128199D01*
G01X2144171Y1633668D02*
Y1651168D01*
X2154215Y1633668D01*
Y1651168D01*
G01X2171496Y1649709D02*
X2170186Y1650585D01*
X2168658Y1651168D01*
X2166911D01*
X2164946Y1650293D01*
X2163418Y1648835D01*
X2162326Y1647084D01*
X2161453Y1644168D01*
X2161234Y1641543D01*
X2161671Y1638918D01*
X2162326Y1637168D01*
X2163636Y1635418D01*
X2165165Y1634251D01*
X2166693Y1633668D01*
X2168221D01*
X2169750Y1634251D01*
X2171060Y1635126D01*
X2172152Y1636292D01*
G01X2188560Y1633668D02*
X2179826D01*
Y1651168D01*
X2188560D01*
G01X2185066Y1642710D02*
X2179826D01*
G01X2219193Y1651168D02*
Y1633668D01*
G01X2214171Y1651168D02*
X2224215D01*
G01X2231234Y1633668D02*
X2236693Y1651168D01*
X2242152Y1633668D01*
G01X2240186Y1639793D02*
X2233199D01*
G01X2255939Y1643001D02*
X2256813Y1643876D01*
X2257468Y1645334D01*
X2257905Y1647377D01*
X2257468Y1649126D01*
X2256595Y1650293D01*
X2255066Y1651168D01*
X2249171D01*
Y1633668D01*
X2256376D01*
X2257905Y1634834D01*
X2258778Y1636585D01*
X2259215Y1638626D01*
X2258778Y1640668D01*
X2257468Y1642418D01*
X2255939Y1643001D01*
X2249171D01*
G01X2267326Y1651168D02*
Y1633668D01*
X2276060D01*
G01X2293560D02*
X2284826D01*
Y1651168D01*
X2293560D01*
G01X2290066Y1642710D02*
X2284826D01*
G01X2306693Y1633085D02*
X2306256Y1633376D01*
Y1633960D01*
X2306693Y1634251D01*
X2307130Y1633960D01*
Y1633376D01*
X2306693Y1633085D01*
G01Y1640959D02*
X2306256Y1641251D01*
Y1641835D01*
X2306693Y1642126D01*
X2307130Y1641835D01*
Y1641251D01*
X2306693Y1640959D01*
G01X2337326Y1651168D02*
Y1633668D01*
X2346060D01*
G01X2359193D02*
X2360721Y1633960D01*
X2362468Y1634834D01*
X2363560Y1636292D01*
X2363996Y1638335D01*
X2363560Y1640376D01*
X2362250Y1642126D01*
X2360285Y1643001D01*
X2358101D01*
X2356791Y1643585D01*
X2355699Y1645043D01*
X2355263Y1647084D01*
X2355918Y1649126D01*
X2357446Y1650585D01*
X2359193Y1651168D01*
X2360939Y1650585D01*
X2362468Y1649126D01*
X2363123Y1647084D01*
X2362686Y1645043D01*
X2361595Y1643585D01*
X2360285Y1643001D01*
X2358101D01*
X2356136Y1642126D01*
X2354826Y1640376D01*
X2354390Y1638335D01*
X2354826Y1636292D01*
X2355918Y1634834D01*
X2357665Y1633960D01*
X2359193Y1633668D01*
G01X2041590Y1566992D02*
X2042899Y1565534D01*
X2044428Y1564660D01*
X2046393Y1564368D01*
X2048358Y1564951D01*
X2049886Y1566118D01*
X2050978Y1568159D01*
X2051196Y1570493D01*
X2050760Y1572826D01*
X2049668Y1574285D01*
X2048139Y1575451D01*
X2046611Y1575743D01*
X2045083Y1575451D01*
X2043118Y1574285D01*
X2043773Y1581868D01*
X2049668D01*
G01X2063893D02*
X2062146Y1581285D01*
X2060836Y1579826D01*
X2059963Y1578077D01*
X2059308Y1575743D01*
X2059090Y1573118D01*
X2059308Y1570493D01*
X2059963Y1568159D01*
X2060836Y1566409D01*
X2062146Y1564951D01*
X2063893Y1564368D01*
X2065639Y1564951D01*
X2066950Y1566409D01*
X2067823Y1568159D01*
X2068478Y1570493D01*
X2068696Y1573118D01*
X2068478Y1575743D01*
X2067823Y1578077D01*
X2066950Y1579826D01*
X2065639Y1581285D01*
X2063893Y1581868D01*
G01X2081393Y1563785D02*
X2080956Y1564076D01*
Y1564660D01*
X2081393Y1564951D01*
X2081830Y1564660D01*
Y1564076D01*
X2081393Y1563785D01*
G01X2098893Y1581868D02*
X2097146Y1581285D01*
X2095836Y1579826D01*
X2094963Y1578077D01*
X2094308Y1575743D01*
X2094090Y1573118D01*
X2094308Y1570493D01*
X2094963Y1568159D01*
X2095836Y1566409D01*
X2097146Y1564951D01*
X2098893Y1564368D01*
X2100639Y1564951D01*
X2101950Y1566409D01*
X2102823Y1568159D01*
X2103478Y1570493D01*
X2103696Y1573118D01*
X2103478Y1575743D01*
X2102823Y1578077D01*
X2101950Y1579826D01*
X2100639Y1581285D01*
X2098893Y1581868D01*
G01X2188593Y1616518D02*
X2191649Y1599018D01*
X2195143Y1616518D01*
X2198636Y1599018D01*
X2201693Y1616518D01*
G01X2210023D02*
X2215263D01*
G01X2212643D02*
Y1599018D01*
G01X2210023D02*
X2215263D01*
G01X2225340D02*
Y1616518D01*
X2229706D01*
X2231453Y1615643D01*
X2232763Y1614476D01*
X2233855Y1612727D01*
X2234728Y1610684D01*
X2234946Y1607768D01*
X2234728Y1604851D01*
X2233855Y1602809D01*
X2232763Y1601059D01*
X2231453Y1599893D01*
X2229706Y1599018D01*
X2225340D01*
G01X2247643Y1616518D02*
Y1599018D01*
G01X2242621Y1616518D02*
X2252665D01*
G01X2260558Y1599018D02*
Y1616518D01*
G01X2269728D02*
Y1599018D01*
G01Y1607768D02*
X2260558D01*
G01X2281551Y1593185D02*
X2279368Y1596101D01*
X2278276Y1599018D01*
Y1610684D01*
X2279368Y1613601D01*
X2281551Y1616518D01*
G01X2293593Y1599018D02*
Y1610684D01*
G01Y1607476D02*
X2294248Y1608935D01*
X2295340Y1610101D01*
X2296868Y1610684D01*
X2298396Y1610101D01*
X2299488Y1608935D01*
X2300143Y1607476D01*
Y1599018D01*
G01Y1607476D02*
X2300798Y1608935D01*
X2301889Y1610101D01*
X2303418Y1610684D01*
X2304946Y1610101D01*
X2306038Y1608935D01*
X2306693Y1607185D01*
Y1599018D01*
G01X2317643Y1610684D02*
Y1599018D01*
G01Y1615351D02*
X2317206Y1615643D01*
Y1616226D01*
X2317643Y1616518D01*
X2318080Y1616226D01*
Y1615643D01*
X2317643Y1615351D01*
G01X2335143Y1599018D02*
Y1616518D01*
G01X2349368Y1601059D02*
X2350460Y1599893D01*
X2351988Y1599018D01*
X2353298D01*
X2354608Y1599601D01*
X2355481Y1600476D01*
X2355918Y1601642D01*
X2355700Y1603393D01*
X2354826Y1604268D01*
X2350896Y1606018D01*
X2350023Y1608060D01*
X2350460Y1609518D01*
X2351333Y1610393D01*
X2352643Y1610684D01*
X2353953Y1610393D01*
X2355263Y1609518D01*
G01X2371235Y1593185D02*
X2373418Y1596101D01*
X2374510Y1599018D01*
Y1610684D01*
X2373418Y1613601D01*
X2371235Y1616518D01*
G01X2259013Y1564368D02*
Y1581868D01*
X2250934Y1569326D01*
X2261852D01*
G01X2273893Y1563785D02*
X2273456Y1564076D01*
Y1564660D01*
X2273893Y1564951D01*
X2274330Y1564660D01*
Y1564076D01*
X2273893Y1563785D01*
G01X2290956Y1564368D02*
X2291393Y1568159D01*
X2292048Y1571368D01*
X2292921Y1574285D01*
X2294013Y1577493D01*
X2295760Y1581868D01*
X2287026D01*
G01X2304090Y1566992D02*
X2305399Y1565534D01*
X2306928Y1564660D01*
X2308893Y1564368D01*
X2310858Y1564951D01*
X2312386Y1566118D01*
X2313478Y1568159D01*
X2313696Y1570493D01*
X2313260Y1572826D01*
X2312168Y1574285D01*
X2310639Y1575451D01*
X2309111Y1575743D01*
X2307583Y1575451D01*
X2305618Y1574285D01*
X2306273Y1581868D01*
X2312168D01*
G01X2431393Y1616518D02*
Y1599018D01*
G01X2426371Y1616518D02*
X2436415D01*
G01X2448893Y1599018D02*
Y1606893D01*
X2444526Y1616518D01*
G01X2453260D02*
X2448893Y1606893D01*
G01X2462026Y1599018D02*
Y1616518D01*
X2467266D01*
X2469013Y1615643D01*
X2470323Y1613601D01*
X2470760Y1611268D01*
X2470323Y1608935D01*
X2469231Y1607185D01*
X2467266Y1606309D01*
X2462026D01*
G01X2488260Y1599018D02*
X2479526D01*
Y1616518D01*
X2488260D01*
G01X2484766Y1608060D02*
X2479526D01*
G01X2444308Y1566701D02*
X2446055Y1565243D01*
X2448020Y1564368D01*
X2449766D01*
X2451513Y1565243D01*
X2452823Y1566701D01*
X2453478Y1568743D01*
X2453041Y1570784D01*
X2451950Y1572535D01*
X2449985Y1573701D01*
X2447365Y1574285D01*
X2445836Y1575451D01*
X2445181Y1577493D01*
X2445618Y1579535D01*
X2446710Y1580993D01*
X2448238Y1581868D01*
X2449766D01*
X2451295Y1581285D01*
X2452605Y1579826D01*
G01X2470760Y1564368D02*
X2462026D01*
Y1581868D01*
X2470760D01*
G01X2467266Y1573410D02*
X2462026D01*
G01X2532026Y1599018D02*
Y1616518D01*
X2537485D01*
X2539231Y1615643D01*
X2540323Y1614476D01*
X2540760Y1612143D01*
X2540323Y1609809D01*
X2539013Y1608351D01*
X2537485Y1607476D01*
X2532026D01*
G01X2537485D02*
X2540760Y1599018D01*
G01X2550618Y1606893D02*
X2557605D01*
X2556950Y1608935D01*
X2555858Y1610101D01*
X2554330Y1610684D01*
X2552801Y1610393D01*
X2551491Y1609518D01*
X2550618Y1607476D01*
X2550181Y1605726D01*
Y1603976D01*
X2550618Y1602226D01*
X2551710Y1600476D01*
X2553020Y1599310D01*
X2554548Y1599018D01*
X2556076Y1599601D01*
X2557605Y1601351D01*
G01X2570083Y1599018D02*
Y1613893D01*
X2570520Y1615351D01*
X2571393Y1616226D01*
X2572703Y1616518D01*
X2574013Y1615935D01*
X2574668Y1614476D01*
G01X2572048Y1609518D02*
X2567681D01*
G01X2588893Y1598435D02*
X2588456Y1598726D01*
Y1599310D01*
X2588893Y1599601D01*
X2589330Y1599310D01*
Y1598726D01*
X2588893Y1598435D01*
G01X2619526Y1599018D02*
Y1616518D01*
X2624766D01*
X2626513Y1615643D01*
X2627823Y1613601D01*
X2628260Y1611268D01*
X2627823Y1608935D01*
X2626731Y1607185D01*
X2624766Y1606309D01*
X2619526D01*
G01X2641393Y1599018D02*
Y1616518D01*
G01X2662823Y1599018D02*
Y1610684D01*
G01Y1608643D02*
X2661950Y1609809D01*
X2660639Y1610393D01*
X2659111Y1610684D01*
X2657583Y1610101D01*
X2656273Y1608935D01*
X2655399Y1607185D01*
X2654963Y1604851D01*
X2655399Y1602518D01*
X2656273Y1600768D01*
X2657583Y1599601D01*
X2659111Y1599018D01*
X2660639Y1599310D01*
X2661950Y1600184D01*
X2662823Y1601351D01*
G01X2672681Y1599018D02*
Y1610684D01*
G01Y1607768D02*
X2673555Y1609226D01*
X2674865Y1610393D01*
X2676611Y1610684D01*
X2678139Y1610393D01*
X2679450Y1609226D01*
X2680105Y1607185D01*
Y1599018D01*
G01X2690618Y1606893D02*
X2697605D01*
X2696950Y1608935D01*
X2695858Y1610101D01*
X2694330Y1610684D01*
X2692801Y1610393D01*
X2691491Y1609518D01*
X2690618Y1607476D01*
X2690181Y1605726D01*
Y1603976D01*
X2690618Y1602226D01*
X2691710Y1600476D01*
X2693020Y1599310D01*
X2694548Y1599018D01*
X2696076Y1599601D01*
X2697605Y1601351D01*
G01X2575776Y1581868D02*
Y1564368D01*
X2584510D01*
G01X2597206D02*
X2597643Y1568159D01*
X2598298Y1571368D01*
X2599171Y1574285D01*
X2600263Y1577493D01*
X2602010Y1581868D01*
X2593276D01*
G01X2611213Y1563785D02*
X2619073Y1581868D01*
G01X2628276D02*
Y1564368D01*
X2637010D01*
G01X2646431Y1566409D02*
X2647960Y1564951D01*
X2649706Y1564368D01*
X2651453Y1564951D01*
X2652981Y1566701D01*
X2654073Y1569326D01*
X2654510Y1571951D01*
Y1575159D01*
X2654073Y1577784D01*
X2652981Y1580118D01*
X2651671Y1581285D01*
X2650143Y1581868D01*
X2648396Y1581285D01*
X2647086Y1580118D01*
X2646213Y1578368D01*
X2645776Y1576034D01*
X2646213Y1573993D01*
X2647305Y1571951D01*
X2648615Y1570784D01*
X2650143Y1570493D01*
X2651889Y1571076D01*
X2653200Y1572535D01*
X2654510Y1575159D01*
G01X2811693Y1576034D02*
Y1564368D01*
G01Y1580701D02*
X2811256Y1580993D01*
Y1581576D01*
X2811693Y1581868D01*
X2812130Y1581576D01*
Y1580993D01*
X2811693Y1580701D01*
G01X2825918Y1566409D02*
X2827010Y1565243D01*
X2828538Y1564368D01*
X2829848D01*
X2831158Y1564951D01*
X2832031Y1565826D01*
X2832468Y1566992D01*
X2832250Y1568743D01*
X2831376Y1569618D01*
X2827446Y1571368D01*
X2826573Y1573410D01*
X2827010Y1574868D01*
X2827883Y1575743D01*
X2829193Y1576034D01*
X2830503Y1575743D01*
X2831813Y1574868D01*
G01X2859171Y1564368D02*
Y1581868D01*
X2869215Y1564368D01*
Y1581868D01*
G01X2881693Y1564368D02*
X2879946Y1564660D01*
X2878418Y1565826D01*
X2877108Y1567576D01*
X2876234Y1569618D01*
X2875798Y1571951D01*
Y1574285D01*
X2876234Y1576618D01*
X2877108Y1578660D01*
X2878418Y1580409D01*
X2879946Y1581576D01*
X2881693Y1581868D01*
X2883439Y1581576D01*
X2884968Y1580409D01*
X2886278Y1578660D01*
X2887152Y1576618D01*
X2887588Y1574285D01*
Y1571951D01*
X2887152Y1569618D01*
X2886278Y1567576D01*
X2884968Y1565826D01*
X2883439Y1564660D01*
X2881693Y1564368D01*
G01X2899193Y1581868D02*
Y1564368D01*
G01X2894171Y1581868D02*
X2904215D01*
G01X2930481Y1576034D02*
Y1567868D01*
X2931355Y1565826D01*
X2932665Y1564660D01*
X2934193Y1564368D01*
X2935721Y1564660D01*
X2937031Y1565826D01*
X2937905Y1567868D01*
G01Y1564368D02*
Y1576034D01*
G01X2948418Y1566409D02*
X2949510Y1565243D01*
X2951038Y1564368D01*
X2952348D01*
X2953658Y1564951D01*
X2954531Y1565826D01*
X2954968Y1566992D01*
X2954750Y1568743D01*
X2953876Y1569618D01*
X2949946Y1571368D01*
X2949073Y1573410D01*
X2949510Y1574868D01*
X2950383Y1575743D01*
X2951693Y1576034D01*
X2953003Y1575743D01*
X2954313Y1574868D01*
G01X2965918Y1572243D02*
X2972905D01*
X2972250Y1574285D01*
X2971158Y1575451D01*
X2969630Y1576034D01*
X2968101Y1575743D01*
X2966791Y1574868D01*
X2965918Y1572826D01*
X2965481Y1571076D01*
Y1569326D01*
X2965918Y1567576D01*
X2967010Y1565826D01*
X2968320Y1564660D01*
X2969848Y1564368D01*
X2971376Y1564951D01*
X2972905Y1566701D01*
G01X2990623Y1581868D02*
Y1564368D01*
G01Y1566992D02*
X2989750Y1565534D01*
X2988439Y1564660D01*
X2986911Y1564368D01*
X2985165Y1564951D01*
X2983855Y1566409D01*
X2982981Y1568159D01*
X2982763Y1570201D01*
X2982981Y1572243D01*
X2983855Y1573993D01*
X2985165Y1575451D01*
X2986911Y1576034D01*
X2988439Y1575743D01*
X2989531Y1575159D01*
X2990623Y1573993D01*
G01X2736890Y1598435D02*
X2746496Y1611268D01*
G01X2741693Y1613601D02*
Y1596101D01*
G01X2746496Y1598435D02*
X2736890Y1611268D01*
G01X2735143Y1604851D02*
X2748243D01*
G01X2773855D02*
X2779531D01*
G01X2806890Y1599018D02*
Y1616518D01*
X2811256D01*
X2813003Y1615643D01*
X2814313Y1614476D01*
X2815405Y1612727D01*
X2816278Y1610684D01*
X2816496Y1607768D01*
X2816278Y1604851D01*
X2815405Y1602809D01*
X2814313Y1601059D01*
X2813003Y1599893D01*
X2811256Y1599018D01*
X2806890D01*
G01X2825918Y1606893D02*
X2832905D01*
X2832250Y1608935D01*
X2831158Y1610101D01*
X2829630Y1610684D01*
X2828101Y1610393D01*
X2826791Y1609518D01*
X2825918Y1607476D01*
X2825481Y1605726D01*
Y1603976D01*
X2825918Y1602226D01*
X2827010Y1600476D01*
X2828320Y1599310D01*
X2829848Y1599018D01*
X2831376Y1599601D01*
X2832905Y1601351D01*
G01X2842981Y1599018D02*
Y1610684D01*
G01Y1607768D02*
X2843855Y1609226D01*
X2845165Y1610393D01*
X2846911Y1610684D01*
X2848439Y1610393D01*
X2849750Y1609226D01*
X2850405Y1607185D01*
Y1599018D01*
G01X2864193D02*
X2862883Y1599310D01*
X2861573Y1600476D01*
X2860699Y1602518D01*
X2860263Y1604851D01*
X2860699Y1607185D01*
X2861573Y1609226D01*
X2862883Y1610393D01*
X2864193Y1610684D01*
X2865503Y1610393D01*
X2866813Y1609226D01*
X2867686Y1607185D01*
X2867905Y1604851D01*
X2867686Y1602518D01*
X2866813Y1600476D01*
X2865503Y1599310D01*
X2864193Y1599018D01*
G01X2881693Y1616518D02*
Y1599018D01*
G01X2878636Y1610684D02*
X2884750D01*
G01X2895918Y1606893D02*
X2902905D01*
X2902250Y1608935D01*
X2901158Y1610101D01*
X2899630Y1610684D01*
X2898101Y1610393D01*
X2896791Y1609518D01*
X2895918Y1607476D01*
X2895481Y1605726D01*
Y1603976D01*
X2895918Y1602226D01*
X2897010Y1600476D01*
X2898320Y1599310D01*
X2899848Y1599018D01*
X2901376Y1599601D01*
X2902905Y1601351D01*
G01X2913418Y1601059D02*
X2914510Y1599893D01*
X2916038Y1599018D01*
X2917348D01*
X2918658Y1599601D01*
X2919531Y1600476D01*
X2919968Y1601642D01*
X2919750Y1603393D01*
X2918876Y1604268D01*
X2914946Y1606018D01*
X2914073Y1608060D01*
X2914510Y1609518D01*
X2915383Y1610393D01*
X2916693Y1610684D01*
X2918003Y1610393D01*
X2919313Y1609518D01*
G01X2951693Y1616518D02*
Y1599018D01*
G01X2948636Y1610684D02*
X2954750D01*
G01X2965481Y1599018D02*
Y1616518D01*
G01Y1608060D02*
X2966573Y1609518D01*
X2967665Y1610393D01*
X2969411Y1610684D01*
X2970721Y1610393D01*
X2972250Y1609226D01*
X2972905Y1607476D01*
Y1599018D01*
G01X2990623D02*
Y1610684D01*
G01Y1608643D02*
X2989750Y1609809D01*
X2988439Y1610393D01*
X2986911Y1610684D01*
X2985383Y1610101D01*
X2984073Y1608935D01*
X2983199Y1607185D01*
X2982763Y1604851D01*
X2983199Y1602518D01*
X2984073Y1600768D01*
X2985383Y1599601D01*
X2986911Y1599018D01*
X2988439Y1599310D01*
X2989750Y1600184D01*
X2990623Y1601351D01*
G01X3004193Y1616518D02*
Y1599018D01*
G01X3001136Y1610684D02*
X3007250D01*
G01X3039193Y1616518D02*
Y1599018D01*
G01X3036136Y1610684D02*
X3042250D01*
G01X3052981Y1599018D02*
Y1616518D01*
G01Y1608060D02*
X3054073Y1609518D01*
X3055165Y1610393D01*
X3056911Y1610684D01*
X3058221Y1610393D01*
X3059750Y1609226D01*
X3060405Y1607476D01*
Y1599018D01*
G01X3074193Y1610684D02*
Y1599018D01*
G01Y1615351D02*
X3073756Y1615643D01*
Y1616226D01*
X3074193Y1616518D01*
X3074630Y1616226D01*
Y1615643D01*
X3074193Y1615351D01*
G01X3088418Y1601059D02*
X3089510Y1599893D01*
X3091038Y1599018D01*
X3092348D01*
X3093658Y1599601D01*
X3094531Y1600476D01*
X3094968Y1601642D01*
X3094750Y1603393D01*
X3093876Y1604268D01*
X3089946Y1606018D01*
X3089073Y1608060D01*
X3089510Y1609518D01*
X3090383Y1610393D01*
X3091693Y1610684D01*
X3093003Y1610393D01*
X3094313Y1609518D01*
G01X3124073Y1616518D02*
X3129313D01*
G01X3126693D02*
Y1599018D01*
G01X3124073D02*
X3129313D01*
G01X3137643D02*
Y1610684D01*
G01Y1607476D02*
X3138298Y1608935D01*
X3139390Y1610101D01*
X3140918Y1610684D01*
X3142446Y1610101D01*
X3143538Y1608935D01*
X3144193Y1607476D01*
Y1599018D01*
G01Y1607476D02*
X3144848Y1608935D01*
X3145939Y1610101D01*
X3147468Y1610684D01*
X3148996Y1610101D01*
X3150088Y1608935D01*
X3150743Y1607185D01*
Y1599018D01*
G01X3157763Y1593185D02*
Y1610684D01*
G01Y1608060D02*
X3158855Y1609518D01*
X3159946Y1610393D01*
X3161693Y1610684D01*
X3163221Y1610393D01*
X3164750Y1608935D01*
X3165405Y1606893D01*
X3165623Y1604851D01*
X3165405Y1602809D01*
X3164750Y1600768D01*
X3163439Y1599601D01*
X3161693Y1599018D01*
X3160165Y1599310D01*
X3158636Y1600184D01*
X3157763Y1601351D01*
G01X3175918Y1606893D02*
X3182905D01*
X3182250Y1608935D01*
X3181158Y1610101D01*
X3179630Y1610684D01*
X3178101Y1610393D01*
X3176791Y1609518D01*
X3175918Y1607476D01*
X3175481Y1605726D01*
Y1603976D01*
X3175918Y1602226D01*
X3177010Y1600476D01*
X3178320Y1599310D01*
X3179848Y1599018D01*
X3181376Y1599601D01*
X3182905Y1601351D01*
G01X3200623Y1616518D02*
Y1599018D01*
G01Y1601642D02*
X3199750Y1600184D01*
X3198439Y1599310D01*
X3196911Y1599018D01*
X3195165Y1599601D01*
X3193855Y1601059D01*
X3192981Y1602809D01*
X3192763Y1604851D01*
X3192981Y1606893D01*
X3193855Y1608643D01*
X3195165Y1610101D01*
X3196911Y1610684D01*
X3198439Y1610393D01*
X3199531Y1609809D01*
X3200623Y1608643D01*
G01X3218123Y1599018D02*
Y1610684D01*
G01Y1608643D02*
X3217250Y1609809D01*
X3215939Y1610393D01*
X3214411Y1610684D01*
X3212883Y1610101D01*
X3211573Y1608935D01*
X3210699Y1607185D01*
X3210263Y1604851D01*
X3210699Y1602518D01*
X3211573Y1600768D01*
X3212883Y1599601D01*
X3214411Y1599018D01*
X3215939Y1599310D01*
X3217250Y1600184D01*
X3218123Y1601351D01*
G01X3227981Y1599018D02*
Y1610684D01*
G01Y1607768D02*
X3228855Y1609226D01*
X3230165Y1610393D01*
X3231911Y1610684D01*
X3233439Y1610393D01*
X3234750Y1609226D01*
X3235405Y1607185D01*
Y1599018D01*
G01X3252686Y1609226D02*
X3251158Y1610393D01*
X3249848Y1610684D01*
X3248101Y1610101D01*
X3246791Y1608935D01*
X3245918Y1606893D01*
X3245699Y1604851D01*
X3245918Y1602809D01*
X3246791Y1601059D01*
X3248101Y1599601D01*
X3249848Y1599018D01*
X3251376Y1599601D01*
X3252686Y1600768D01*
G01X3263418Y1606893D02*
X3270405D01*
X3269750Y1608935D01*
X3268658Y1610101D01*
X3267130Y1610684D01*
X3265601Y1610393D01*
X3264291Y1609518D01*
X3263418Y1607476D01*
X3262981Y1605726D01*
Y1603976D01*
X3263418Y1602226D01*
X3264510Y1600476D01*
X3265820Y1599310D01*
X3267348Y1599018D01*
X3268876Y1599601D01*
X3270405Y1601351D01*
G01X0Y-137756D02*
G03X15000Y-152756I15000J0D01*
G01X0Y-137756D02*
G03X15000Y-152756I15000J0D01*
G01X0Y-11811D02*
Y-137756D01*
G01Y-11811D02*
Y-137756D01*
G01X854331Y-152756D02*
X15000D01*
G01X854331D02*
X15000D01*
G01X23622Y-7874D02*
G03Y0I0J3937D01*
G01Y-7874D02*
G03Y0I0J3937D01*
G01X0Y3937D02*
G03X3937Y0I3937J0D01*
G01Y-7874D02*
X23622D01*
G01X0Y3937D02*
G03X3937Y0I3937J0D01*
G01Y-7874D02*
X23622D01*
G01X3937D02*
G03X0Y-11811I0J-3937D01*
G01X3937Y-7874D02*
G03X0Y-11811I0J-3937D01*
G01X3937Y0D02*
X397638D01*
G01X3937D02*
X397638D01*
G01X0Y1370866D02*
Y3937D01*
G01Y1370866D02*
Y3937D01*
G01X3937Y1374803D02*
G03X0Y1370866I0J-3937D01*
G01X3937Y1374803D02*
G03X0Y1370866I0J-3937D01*
G01X23622Y1374803D02*
G03Y1382677I0J3937D01*
G01Y1374803D02*
G03Y1382677I0J3937D01*
G01X3937D02*
X23622D01*
G01X0Y1386614D02*
G03X3937Y1382677I3937J0D01*
G01D02*
X23622D01*
G01X0Y1386614D02*
G03X3937Y1382677I3937J0D01*
G01Y1374803D02*
X746850D01*
G01D02*
X3937D01*
G01X0Y1386614D02*
Y1643268D01*
G01Y1386614D02*
Y1643268D01*
G01X15000Y1658268D02*
G03X0Y1643268I0J-15000D01*
G01X15000Y1658268D02*
G03X0Y1643268I0J-15000D01*
G01X775591Y1658268D02*
X15000D01*
G01X775591D02*
X15000D01*
G01X54331Y-7874D02*
X323228D01*
G01X54331D02*
X323228D01*
G01X54331Y0D02*
G03Y-7874I0J-3937D01*
G01Y0D02*
G03Y-7874I0J-3937D01*
G01Y1382677D02*
G03Y1374803I0J-3937D01*
G01Y1382677D02*
G03Y1374803I0J-3937D01*
G01Y1382677D02*
X353740D01*
G01X54331D02*
X353740D01*
G01X114295Y378885D02*
G03X148106I16905J-13531D01*
G01X114295D02*
G03X148106I16905J-13531D01*
G01X114295D02*
G03X121220Y392016I-30737J24602D01*
G01X114295Y378885D02*
G03X121220Y392016I-30737J24602D01*
G01X114295Y831641D02*
G03X121220Y844772I-30737J24601D01*
G01X114295Y831641D02*
G03X121220Y844772I-30737J24602D01*
G01X114295Y831641D02*
G03X148106I16905J-13531D01*
G01X114295D02*
G03X148106I16905J-13531D01*
G01X114295Y1284397D02*
G03X148106I16905J-13531D01*
G01X114295D02*
G03X148106I16905J-13531D01*
G01X114295D02*
G03X121220Y1297528I-30737J24601D01*
G01X114295Y1284397D02*
G03X121220Y1297528I-30737J24602D01*
G01X141181Y392016D02*
G03X121220I-9980J-3039D01*
G01X141181D02*
G03X148106Y378885I37662J11471D01*
G01X141181Y392016D02*
G03X121220I-9980J-3039D01*
G01X141181D02*
G03X148106Y378885I37662J11471D01*
G01X141181Y844772D02*
G03X148106Y831641I37662J11471D01*
G01X141181Y844772D02*
G03X148106Y831641I37662J11471D01*
G01X141181Y844772D02*
G03X121220I-9980J-3040D01*
G01X141181D02*
G03X121220I-9980J-3039D01*
G01X141181Y1297528D02*
G03X121220I-9980J-3040D01*
G01X141181D02*
G03X148106Y1284397I37662J11471D01*
G01X141181Y1297528D02*
G03X121220I-9980J-3040D01*
G01X141181D02*
G03X148106Y1284397I37662J11471D01*
G01X323228Y-7874D02*
G03Y0I0J3937D01*
G01Y-7874D02*
G03Y0I0J3937D01*
G01X362598D02*
G03Y-7874I0J-3937D01*
G01Y0D02*
G03Y-7874I0J-3937D01*
G01X362327Y378885D02*
G03X396138I16905J-13531D01*
G01X362327D02*
G03X396138I16905J-13531D01*
G01X362327D02*
G03X369252Y392016I-30737J24602D01*
G01X362327Y378885D02*
G03X369252Y392016I-30737J24602D01*
G01X362327Y831641D02*
G03X369252Y844772I-30737J24602D01*
G01X362327Y831641D02*
G03X369252Y844772I-30737J24602D01*
G01X362327Y831641D02*
G03X396138I16905J-13531D01*
G01X362327D02*
G03X396138I16905J-13531D01*
G01X362327Y1284397D02*
G03X396138I16905J-13531D01*
G01X362327D02*
G03X396138I16905J-13531D01*
G01X362327D02*
G03X369252Y1297528I-30737J24602D01*
G01X362327Y1284397D02*
G03X369252Y1297528I-30737J24602D01*
G01X353740Y1374803D02*
G03Y1382677I0J3937D01*
G01Y1374803D02*
G03Y1382677I0J3937D01*
G01X401575Y3937D02*
Y55118D01*
G01X397638Y0D02*
G03X401575Y3937I0J3937D01*
G01X409449D02*
Y51181D01*
G01X397638Y-7874D02*
G03X409449Y3937I0J11811D01*
G01X397638Y0D02*
G03X401575Y3937I0J3937D01*
G01D02*
Y55118D01*
G01X409449Y3937D02*
Y51181D01*
G01X397638Y-7874D02*
G03X409449Y3937I0J11811D01*
G01X362598Y-7874D02*
X397638D01*
G01X362598D02*
X397638D01*
G01X405512Y59055D02*
G03X401575Y55118I0J-3937D01*
G01X405512Y59055D02*
G03X401575Y55118I0J-3937D01*
G01X405512Y59055D02*
X586614D01*
G01X409449Y51181D02*
X582677D01*
G01X405512Y59055D02*
X586614D01*
G01X409449Y51181D02*
X582677D01*
G01X389213Y392016D02*
G03X396138Y378885I37662J11471D01*
G01X389213Y392016D02*
G03X396138Y378885I37662J11471D01*
G01X389213Y392016D02*
G03X369252I-9981J-3039D01*
G01X389213D02*
G03X369252I-9981J-3039D01*
G01X389213Y844772D02*
G03X396138Y831641I37662J11471D01*
G01X389213Y844772D02*
G03X396138Y831641I37662J11471D01*
G01X389213Y844772D02*
G03X369252I-9981J-3040D01*
G01X389213D02*
G03X369252I-9981J-3039D01*
G01X389213Y1297528D02*
G03X396138Y1284397I37662J11471D01*
G01X389213Y1297528D02*
G03X396138Y1284397I37662J11471D01*
G01X389213Y1297528D02*
G03X369252I-9981J-3040D01*
G01X389213D02*
G03X369252I-9981J-3040D01*
G01X393110Y1382677D02*
G03Y1374803I0J-3937D01*
G01Y1382677D02*
X692520D01*
G01X393110D02*
X692520D01*
G01X393110D02*
G03Y1374803I0J-3937D01*
G01X523327Y829921D02*
G03X483169I-20079J0D01*
G01X523327D02*
G03I-20079J0D01*
G01X483169D02*
G03X523327I20079J0D01*
G01X594488Y-7874D02*
X628765D01*
G01X594488D02*
X628765D01*
G01X590551Y55118D02*
Y3937D01*
G01D02*
G03X594488Y0I3937J0D01*
G01X582677Y51181D02*
Y3937D01*
G01D02*
G03X594488Y-7874I11811J0D01*
G01X590551Y55118D02*
Y3937D01*
G01D02*
G03X594488Y0I3937J0D01*
G01X582677Y51181D02*
Y3937D01*
G01D02*
G03X594488Y-7874I11811J0D01*
G01Y0D02*
X783465D01*
G01X594488D02*
X783465D01*
G01X590551Y55118D02*
G03X586614Y59055I-3937J0D01*
G01X590551Y55118D02*
G03X586614Y59055I-3937J0D01*
G01X628765Y-7874D02*
G03Y0I0J3937D01*
G01Y-7874D02*
G03Y0I0J3937D01*
G01X610358Y378885D02*
G03X644169I16906J-13531D01*
G01X610358D02*
G03X644169I16906J-13531D01*
G01X637244Y392016D02*
G03X644169Y378885I37662J11471D01*
G01X637244Y392016D02*
G03X644169Y378885I37662J11471D01*
G01X637244Y392016D02*
G03X617283I-9980J-3039D01*
G01X637244D02*
G03X617283I-9980J-3039D01*
G01X610358Y378885D02*
G03X617283Y392016I-30737J24602D01*
G01X610358Y378885D02*
G03X617283Y392016I-30737J24602D01*
G01X637244Y844772D02*
G03X644169Y831641I37662J11471D01*
G01X637244Y844772D02*
G03X644169Y831641I37662J11471D01*
G01X610358D02*
G03X617283Y844772I-30737J24601D01*
G01X610358Y831641D02*
G03X617283Y844772I-30737J24602D01*
G01X610358Y831641D02*
G03X644169I16906J-13531D01*
G01X610358D02*
G03X644169I16906J-13531D01*
G01X637244Y844772D02*
G03X617283I-9980J-3040D01*
G01X637244D02*
G03X617283I-9980J-3039D01*
G01X610358Y1284397D02*
G03X644169I16906J-13531D01*
G01X610358D02*
G03X644169I16906J-13531D01*
G01X637244Y1297528D02*
G03X644169Y1284397I37662J11471D01*
G01X637244Y1297528D02*
G03X644169Y1284397I37662J11471D01*
G01X610358D02*
G03X617283Y1297528I-30737J24601D01*
G01X637244D02*
G03X617283I-9980J-3040D01*
G01X610358Y1284397D02*
G03X617283Y1297528I-30737J24602D01*
G01X637244D02*
G03X617283I-9980J-3040D01*
G01X659474Y0D02*
G03Y-7874I0J-3937D01*
G01Y0D02*
G03Y-7874I0J-3937D01*
G01D02*
X780203D01*
G01X659474D02*
X780203D01*
G01X692520Y1374803D02*
G03Y1382677I0J3937D01*
G01Y1374803D02*
G03Y1382677I0J3937D01*
G01X746850Y1374803D02*
G03X750787Y1378740I0J3937D01*
G01X746850Y1374803D02*
G03X750787Y1378740I0J3937D01*
G01X723228Y1382677D02*
G03Y1374803I0J-3937D01*
G01Y1382677D02*
X742913D01*
G01X723228D02*
X742913D01*
G01X723228D02*
G03Y1374803I0J-3937D01*
G01X742913Y1464567D02*
Y1382677D01*
G01Y1464567D02*
Y1382677D01*
G01X754724Y1476378D02*
G03X742913Y1464567I0J-11811D01*
G01X754724Y1476378D02*
G03X742913Y1464567I0J-11811D01*
G01X862205Y-7874D02*
X791339D01*
G01X787402Y-3937D02*
G03X791339Y-7874I3937J0D01*
G01X787402Y-3937D02*
G03X791339Y-7874I3937J0D01*
G01D02*
X862205D01*
G01X858268Y-15748D02*
X791339D01*
G01X858268D02*
X791339D01*
G01X787402Y-3937D02*
G03X783465Y0I-3937J0D01*
G01X787402Y-3937D02*
G03X783465Y0I-3937J0D01*
G01X780203Y-7874D02*
G03X791339Y-15748I11136J3937D01*
G01X780203Y-7874D02*
G03X791339Y-15748I11136J3937D01*
G01X779551Y264712D02*
G03X813362I16905J-13531D01*
G01X779551D02*
G03X813362I16905J-13531D01*
G01X779551D02*
G03X786476Y277843I-30737J24601D01*
G01X806437D02*
G03X786476I-9981J-3040D01*
G01X779551Y264712D02*
G03X786476Y277843I-30737J24602D01*
G01X806437D02*
G03X786476I-9981J-3040D01*
G01X779551Y737153D02*
G03X786476Y750284I-30737J24601D01*
G01X779551Y737154D02*
G03X786476Y750284I-30736J24602D01*
G01X779551Y737153D02*
G03X813362I16905J-13531D01*
G01X779551D02*
G03X813362I16905J-13531D01*
G01X806437Y750284D02*
G03X786476I-9981J-3040D01*
G01X806437D02*
G03X786476I-9981J-3040D01*
G01X750787Y1464567D02*
Y1378740D01*
G01Y1464567D02*
Y1378740D01*
G01X783465Y1468504D02*
G03X787402Y1472441I0J3937D01*
G01X783465Y1468504D02*
G03X787402Y1472441I0J3937D01*
G01X783465Y1468504D02*
X754724D01*
G01D02*
G03X750787Y1464567I0J-3937D01*
G01X783465Y1468504D02*
X754724D01*
G01D02*
G03X750787Y1464567I0J-3937D01*
G01X779528Y1476378D02*
X754724D01*
G01X779528D02*
X754724D01*
G01X787402Y1654331D02*
Y1472441D01*
G01X779528Y1596063D02*
Y1476378D01*
G01X787402Y1654331D02*
Y1472441D01*
G01X779528Y1596063D02*
Y1476378D01*
G01X787402Y1596063D02*
G03X779528I-3937J0D01*
G01X787402D02*
G03X779528I-3937J0D01*
G01X1216535Y1658268D02*
X791339D01*
G01D02*
G03X787402Y1654331I0J-3937D01*
G01X779528D02*
G03X775591Y1658268I-3937J0D01*
G01X1216535D02*
X791339D01*
G01D02*
G03X787402Y1654331I0J-3937D01*
G01X779528D02*
G03X775591Y1658268I-3937J0D01*
G01X779528Y1654331D02*
Y1626772D01*
G01D02*
G03X787402I3937J0D01*
G01X779528Y1654331D02*
Y1626772D01*
G01D02*
G03X787402I3937J0D01*
G01X806437Y277843D02*
G03X813362Y264712I37662J11471D01*
G01X806437Y277843D02*
G03X813362Y264712I37662J11471D01*
G01X806437Y750284D02*
G03X813362Y737153I37662J11471D01*
G01X806437Y750284D02*
G03X813362Y737154I37661J11472D01*
G01X866142Y-148819D02*
Y-11811D01*
G01Y-148819D02*
G03X870079Y-152756I3937J0D01*
G01X866142Y-11811D02*
Y-148819D01*
G01D02*
G03X870079Y-152756I3937J0D01*
G01X866142Y-129134D02*
G03X858268I-3937J0D01*
G01X866142D02*
G03X858268I-3937J0D01*
G01Y-148819D02*
Y-129134D01*
G01X854331Y-152756D02*
G03X858268Y-148819I0J3937D01*
G01D02*
Y-129134D01*
G01X854331Y-152756D02*
G03X858268Y-148819I0J3937D01*
G01X1177165Y-152756D02*
X870079D01*
G01D02*
X1177165D01*
G01X858268Y-98425D02*
Y-15748D01*
G01Y-98425D02*
Y-15748D01*
G01Y-98425D02*
G03X866142I3937J0D01*
G01X858268D02*
G03X866142I3937J0D01*
G01Y-11811D02*
G03X862205Y-7874I-3937J0D01*
G01X866142Y-11811D02*
G03X862205Y-7874I-3937J0D01*
G01X927032Y-57820D02*
G03X962731I17850J-12259D01*
G01X927032Y-57821D02*
G03X962732I17850J-12258D01*
G01X927032Y-57820D02*
G03X935199Y-42571I-64908J44575D01*
G01X954565D02*
G03X935199I-9683J-3885D01*
G01X927032Y-57821D02*
G03X935199Y-42571I-64909J44573D01*
G01X954564D02*
G03X935199I-9682J-3885D01*
G01X944512Y1089122D02*
G03X978323I16905J-13531D01*
G01X944512Y1089121D02*
G03X978323I16905J-13531D01*
G01X944512Y1431641D02*
G03X978323I16905J-13531D01*
G01X944512D02*
G03X978323I16905J-13531D01*
G01X954565Y-42571D02*
G03X962731Y-57820I73077J29322D01*
G01X954564Y-42570D02*
G03X962732Y-57821I73076J29324D01*
G01X971398Y1102252D02*
G03X978323Y1089122I37661J11472D01*
G01X971398Y1102252D02*
G03X978323Y1089121I37662J11471D01*
G01X971398Y1102252D02*
G03X951437I-9980J-3039D01*
G01X971398D02*
G03X951437I-9980J-3039D01*
G01X944512Y1089122D02*
G03X951437Y1102252I-30737J24602D01*
G01X944512Y1089121D02*
G03X951437Y1102252I-30737J24602D01*
G01X971398Y1444772D02*
G03X978323Y1431641I37662J11471D01*
G01X971398Y1444772D02*
G03X978323Y1431641I37662J11471D01*
G01X971398Y1444772D02*
G03X951437I-9980J-3040D01*
G01X944512Y1431641D02*
G03X951437Y1444772I-30737J24602D01*
G01X944512Y1431641D02*
G03X951437Y1444772I-30737J24602D01*
G01X971398D02*
G03X951437I-9980J-3039D01*
G01X1181102Y-148819D02*
Y-3937D01*
G01X1177165Y-152756D02*
G03X1181102Y-148819I0J3937D01*
G01X1177165Y-152756D02*
G03X1181102Y-148819I0J3937D01*
G01D02*
Y-3937D01*
G01Y-94488D02*
G03X1188976I3937J0D01*
G01X1181102D02*
G03X1188976I3937J0D01*
G01Y-125197D02*
G03X1181102I-3937J0D01*
G01X1188976D02*
G03X1181102I-3937J0D01*
G01X1185039Y0D02*
G03X1181102Y-3937I0J-3937D01*
G01X1185039Y0D02*
G03X1181102Y-3937I0J-3937D01*
G01X1164984Y557626D02*
G03X1198795I16906J-13531D01*
G01X1164984Y557625D02*
G03X1198795I16906J-13531D01*
G01X1191870Y570756D02*
G03X1171909I-9980J-3039D01*
G01X1191870D02*
G03X1171909I-9980J-3039D01*
G01X1164984Y557626D02*
G03X1171909Y570756I-30736J24602D01*
G01X1164984Y557625D02*
G03X1171909Y570756I-30737J24602D01*
G01X1164984Y971011D02*
G03X1198795I16906J-13531D01*
G01X1164984D02*
G03X1198795I16906J-13531D01*
G01X1191870Y984142D02*
G03X1171909I-9980J-3040D01*
G01X1191870D02*
G03X1171909I-9980J-3039D01*
G01X1164984Y971011D02*
G03X1171909Y984142I-30737J24602D01*
G01X1164984Y971011D02*
G03X1171909Y984142I-30737J24602D01*
G01X1164173Y1378740D02*
Y1468504D01*
G01X1930906Y1374803D02*
X1168110D01*
G01X1164173Y1378740D02*
G03X1168110Y1374803I3937J0D01*
G01X1172047Y1382677D02*
Y1464567D01*
G01X1195669Y1382677D02*
X1172047D01*
G01X1930906Y1374803D02*
X1168110D01*
G01X1164173Y1378740D02*
G03X1168110Y1374804I3937J1D01*
G01X1164173Y1378740D02*
Y1468504D01*
G01X1172047Y1382677D02*
Y1464567D01*
G01X1195669Y1382677D02*
X1172047D01*
G01X1168110Y1472441D02*
G03X1164173Y1468504I0J-3937D01*
G01X1168110Y1472441D02*
G03X1164173Y1468504I0J-3937D01*
G01X1172047Y1464567D02*
X1216535D01*
G01X1172047D02*
X1216535D01*
G01X1168110Y1472441D02*
X1216535D01*
G01X1168110D02*
X1216535D01*
G01X1164984Y1561563D02*
G03X1171909Y1574693I-30736J24602D01*
G01X1164984Y1561562D02*
G03X1171909Y1574693I-30737J24602D01*
G01X1164984Y1561563D02*
G03X1198795I16906J-13531D01*
G01X1164984Y1561562D02*
G03X1198795I16906J-13531D01*
G01X1191870Y1574693D02*
G03X1171909I-9980J-3039D01*
G01X1191870D02*
G03X1171909I-9980J-3039D01*
G01X1188976Y-148819D02*
Y-125197D01*
G01Y-148819D02*
G03X1192913Y-152756I3937J0D01*
G01X1188976Y-148819D02*
Y-125197D01*
G01Y-148819D02*
G03X1192913Y-152756I3937J0D01*
G01D02*
X1919843D01*
G01X1192913D02*
X1919843D01*
G01X1188976Y-94488D02*
Y-7874D01*
G01Y-94488D02*
Y-7874D01*
G01X1185039Y0D02*
X1366142D01*
G01X1188976Y-7874D02*
X1315748D01*
G01X1185039Y0D02*
X1366142D01*
G01X1188976Y-7874D02*
X1315748D01*
G01X1191870Y570756D02*
G03X1198795Y557626I37662J11472D01*
G01X1191870Y570756D02*
G03X1198795Y557626I37662J11472D01*
G01X1191870Y984142D02*
G03X1198795Y971011I37662J11471D01*
G01X1191870Y984142D02*
G03X1198795Y971011I37662J11471D01*
G01X1524606Y1382677D02*
X1226378D01*
G01X1524606D02*
X1226378D01*
G01X1195669Y1374803D02*
G03Y1382677I0J3937D01*
G01X1226378D02*
G03Y1374803I0J-3937D01*
G01X1195669D02*
G03Y1382677I0J3937D01*
G01X1226378D02*
G03Y1374803I0J-3937D01*
G01X1216535Y1464567D02*
G03X1228346Y1476378I0J11811D01*
G01X1216535Y1464567D02*
G03X1228346Y1476378I0J11811D01*
G01Y1592126D02*
Y1476378D01*
G01Y1592126D02*
Y1476378D01*
G01X1220472Y1654331D02*
Y1476378D01*
G01X1216535Y1472441D02*
G03X1220472Y1476378I0J3937D01*
G01X1216535Y1472441D02*
G03X1220472Y1476378I0J3937D01*
G01D02*
Y1654331D01*
G01X1191870Y1574693D02*
G03X1198795Y1561563I37662J11472D01*
G01X1191870Y1574693D02*
G03X1198795Y1561562I37662J11471D01*
G01X1228346Y1592126D02*
G03X1220472I-3937J0D01*
G01X1228346D02*
G03X1220472I-3937J0D01*
G01X1232283Y1658268D02*
X1442382D01*
G01X1232283D02*
G03X1228346Y1654331I0J-3937D01*
G01X1232283Y1658268D02*
X1442382D01*
G01X1232283D02*
G03X1228346Y1654331I0J-3937D01*
G01D02*
Y1622835D01*
G01Y1654331D02*
Y1622835D01*
G01X1220472Y1654331D02*
G03X1216535Y1658268I-3937J0D01*
G01X1220472Y1654331D02*
G03X1216535Y1658268I-3937J0D01*
G01X1220472Y1622835D02*
G03X1228346I3937J0D01*
G01X1220472D02*
G03X1228346I3937J0D01*
G01X1284965Y378885D02*
G03X1318776I16906J-13531D01*
G01X1284965D02*
G03X1318775I16905J-13531D01*
G01X1284965Y831641D02*
G03X1318776I16906J-13531D01*
G01X1284965D02*
G03X1318775I16905J-13531D01*
G01X1284965Y1284397D02*
G03X1318776I16906J-13531D01*
G01X1284965D02*
G03X1318775I16905J-13531D01*
G01X1315748Y-7874D02*
G03Y0I0J3937D01*
G01Y-7874D02*
G03Y0I0J3937D01*
G01X1311850Y392016D02*
G03X1291890I-9980J-3040D01*
G01X1311850D02*
G03X1318776Y378885I37662J11473D01*
G01X1311851Y392016D02*
G03X1291890I-9980J-3039D01*
G01X1311851D02*
G03X1318775Y378885I37663J11469D01*
G01X1284965D02*
G03X1291890Y392016I-30737J24602D01*
G01X1284965Y378885D02*
G03X1291890Y392016I-30737J24602D01*
G01X1284965Y831641D02*
G03X1291890Y844772I-30737J24602D01*
G01X1311850D02*
G03X1318776Y831641I37662J11473D01*
G01X1284965D02*
G03X1291890Y844772I-30737J24602D01*
G01X1311851D02*
G03X1318775Y831641I37663J11469D01*
G01X1311850Y844772D02*
G03X1291890I-9980J-3040D01*
G01X1311851D02*
G03X1291890I-9980J-3039D01*
G01X1284965Y1284397D02*
G03X1291890Y1297528I-30737J24602D01*
G01X1311850D02*
G03X1291890I-9980J-3040D01*
G01X1311850D02*
G03X1318776Y1284397I37661J11473D01*
G01X1284965D02*
G03X1291890Y1297528I-30737J24602D01*
G01X1311851D02*
G03X1291890I-9980J-3040D01*
G01X1311851D02*
G03X1318775Y1284397I37663J11469D01*
G01X1377953Y3937D02*
Y51181D01*
G01Y3937D02*
Y51181D01*
G01X1370079Y3937D02*
Y55118D01*
G01X1366142Y0D02*
G03X1370079Y3937I0J3937D01*
G01X1366142Y-7874D02*
G03X1377953Y3937I0J11811D01*
G01X1346457Y-7874D02*
X1366142D01*
G01Y0D02*
G03X1370079Y3937I0J3937D01*
G01D02*
Y55118D01*
G01X1346457Y-7874D02*
X1366142D01*
G01D02*
G03X1377953Y3937I0J11811D01*
G01X1346457Y0D02*
G03Y-7874I0J-3937D01*
G01Y0D02*
G03Y-7874I0J-3937D01*
G01X1374016Y59055D02*
G03X1370079Y55118I0J-3937D01*
G01X1374016Y59056D02*
G03X1370079Y55118I0J-3937D01*
G01X1374016Y59055D02*
X1555118D01*
G01X1377953Y51181D02*
X1551181D01*
G01X1374016Y59055D02*
X1555118D01*
G01X1377953Y51181D02*
X1551181D01*
G01X1442382Y1658268D02*
G03X1450256I3937J0D01*
G01X1442382D02*
G03X1450256I3937J0D01*
G01D02*
X1919843D01*
G01X1450256D02*
X1919843D01*
G01X1562992Y0D02*
X1930906D01*
G01X1559055Y55118D02*
Y3937D01*
G01D02*
G03X1562992Y0I3937J0D01*
G01Y-7874D02*
X1593701D01*
G01X1559055Y55118D02*
Y3937D01*
G01D02*
G03X1562992Y0I3937J0D01*
G01D02*
X1930906D01*
G01X1562992Y-7874D02*
X1593701D01*
G01X1551181Y51181D02*
Y3937D01*
G01D02*
G03X1562992Y-7874I11811J0D01*
G01X1551181Y51181D02*
Y3937D01*
G01D02*
G03X1562992Y-7874I11811J0D01*
G01X1559055Y55118D02*
G03X1555118Y59055I-3937J0D01*
G01X1559055Y55118D02*
G03X1555118Y59055I-3937J0D01*
G01X1532996Y378885D02*
G03X1566807I16906J-13531D01*
G01X1532996D02*
G03X1566807I16906J-13531D01*
G01X1559882Y392016D02*
G03X1566807Y378885I37662J11471D01*
G01X1559882Y392016D02*
G03X1566807Y378885I37662J11471D01*
G01X1559882Y392016D02*
G03X1539921I-9980J-3039D01*
G01X1559882D02*
G03X1539921I-9980J-3039D01*
G01X1532996Y378885D02*
G03X1539921Y392016I-30737J24602D01*
G01X1532996Y378885D02*
G03X1539921Y392016I-30737J24602D01*
G01X1559882Y844772D02*
G03X1566807Y831641I37662J11471D01*
G01X1559882Y844772D02*
G03X1566807Y831641I37662J11471D01*
G01X1532996D02*
G03X1539921Y844772I-30737J24602D01*
G01X1532996Y831641D02*
G03X1539921Y844772I-30737J24602D01*
G01X1532996Y831641D02*
G03X1566807I16906J-13531D01*
G01X1532996D02*
G03X1566807I16906J-13531D01*
G01X1559882Y844772D02*
G03X1539921I-9980J-3040D01*
G01X1559882D02*
G03X1539921I-9980J-3039D01*
G01X1532996Y1284397D02*
G03X1566807I16906J-13531D01*
G01X1532996D02*
G03X1566807I16906J-13531D01*
G01X1559882Y1297528D02*
G03X1566807Y1284397I37662J11471D01*
G01X1559882Y1297528D02*
G03X1566807Y1284397I37662J11471D01*
G01X1559882Y1297528D02*
G03X1539921I-9980J-3040D01*
G01X1532996Y1284397D02*
G03X1539921Y1297528I-30737J24602D01*
G01X1532996Y1284397D02*
G03X1539921Y1297528I-30737J24602D01*
G01X1559882D02*
G03X1539921I-9980J-3040D01*
G01X1563976Y1382677D02*
G03Y1374803I0J-3937D01*
G01Y1382677D02*
G03Y1374803I0J-3937D01*
G01X1524606D02*
G03Y1382677I0J3937D01*
G01Y1374803D02*
G03Y1382677I0J3937D01*
G01X1864567D02*
X1563976D01*
G01X1864567D02*
X1563976D01*
G01X1593701Y-7874D02*
G03Y0I0J3937D01*
G01Y-7874D02*
G03Y0I0J3937D01*
G01X1633071D02*
G03Y-7874I0J-3937D01*
G01D02*
X1880512D01*
G01X1633071D02*
X1880512D01*
G01X1633071Y0D02*
G03Y-7874I0J-3937D01*
G01X1693996Y829921D02*
G03X1653839I-20078J0D01*
G01X1693996D02*
G03I-20079J0D01*
G01X1653839D02*
G03X1693996I20078J0D01*
G01X1781028Y378885D02*
G03X1814839I16906J-13531D01*
G01X1781028D02*
G03X1814838I16905J-13531D01*
G01X1807913Y392016D02*
G03X1814839Y378885I37662J11473D01*
G01X1807914Y392016D02*
G03X1814838Y378885I37663J11469D01*
G01X1807913Y392016D02*
G03X1787953I-9980J-3040D01*
G01X1807914D02*
G03X1787953I-9980J-3039D01*
G01X1781028Y378885D02*
G03X1787953Y392016I-30737J24602D01*
G01X1781028Y378885D02*
G03X1787953Y392016I-30737J24602D01*
G01X1807913Y844772D02*
G03X1814839Y831641I37662J11473D01*
G01X1807914Y844772D02*
G03X1814838Y831641I37663J11469D01*
G01X1781028D02*
G03X1787953Y844772I-30737J24602D01*
G01X1781028Y831641D02*
G03X1787953Y844772I-30737J24602D01*
G01X1781028Y831641D02*
G03X1814839I16906J-13531D01*
G01X1781028D02*
G03X1814838I16905J-13531D01*
G01X1807913Y844772D02*
G03X1787953I-9980J-3040D01*
G01X1807914D02*
G03X1787953I-9980J-3039D01*
G01X1781028Y1284397D02*
G03X1814839I16906J-13531D01*
G01X1781028D02*
G03X1814838I16905J-13531D01*
G01X1807913Y1297528D02*
G03X1814839Y1284397I37661J11473D01*
G01X1807914Y1297528D02*
G03X1814838Y1284397I37663J11469D01*
G01X1807913Y1297528D02*
G03X1787953I-9980J-3040D01*
G01X1781028Y1284397D02*
G03X1787953Y1297528I-30737J24602D01*
G01X1781028Y1284397D02*
G03X1787953Y1297528I-30737J24602D01*
G01X1807914D02*
G03X1787953I-9980J-3040D01*
G01X1911220Y0D02*
G03Y-7874I0J-3937D01*
G01Y0D02*
G03Y-7874I0J-3937D01*
G01X1880512D02*
G03Y0I0J3937D01*
G01Y-7874D02*
G03Y0I0J3937D01*
G01X1930906Y1382677D02*
X1895276D01*
G01D02*
G03Y1374803I0J-3937D01*
G01X1930906Y1382677D02*
X1895276D01*
G01D02*
G03Y1374803I0J-3937D01*
G01X1864567D02*
G03Y1382677I0J3937D01*
G01Y1374803D02*
G03Y1382677I0J3937D01*
G01X1919843Y-152756D02*
G03X1934843Y-137756I0J15000D01*
G01X1919843Y-152756D02*
G03X1934843Y-137756I0J15000D01*
G01Y-11811D02*
Y-137756D01*
G01Y-11811D02*
Y-137756D01*
G01X1930906Y0D02*
G03X1934843Y3937I0J3937D01*
G01X1930906Y0D02*
G03X1934843Y3937I0J3937D01*
G01Y-11811D02*
G03X1930906Y-7874I-3937J0D01*
G01X1934843Y-11811D02*
G03X1930906Y-7874I-3937J0D01*
G01X1911220D02*
X1930906D01*
G01X1911220D02*
X1930906D01*
G01X1934843Y1370866D02*
Y3937D01*
G01D02*
Y1370866D01*
G01D02*
G03X1930906Y1374803I-3937J0D01*
G01X1934843Y1370866D02*
G03X1930906Y1374803I-3937J0D01*
G01Y1382677D02*
G03X1934843Y1386614I0J3937D01*
G01X1930906Y1382677D02*
G03X1934843Y1386614I0J3937D01*
G01D02*
Y1643268D01*
G01Y1386614D02*
Y1643268D01*
G01D02*
G03X1919843Y1658268I-15000J0D01*
G01X1934843Y1643268D02*
G03X1919843Y1658268I-15000J0D01*
G54D12*
G01X439800Y103580D02*
Y130286D01*
G01X436811Y100591D02*
X439800Y103580D01*
G01X453580Y104144D02*
Y136611D01*
G01X450984Y101548D02*
X453580Y104144D01*
G01X450984Y100591D02*
Y101548D01*
G01X455455Y99270D02*
Y124147D01*
G01X458071Y96654D02*
X455455Y99270D01*
G01X439800Y130286D02*
X474313Y164799D01*
G01X453580Y136611D02*
X476817Y159848D01*
G01X455455Y124147D02*
X461392Y130084D01*
G01X510504Y1359747D02*
X422373D01*
G01X511522Y1356522D02*
X418922D01*
G01X502218Y163281D02*
X538805D01*
G01X500700Y164799D02*
X502218Y163281D01*
G01X500307Y158190D02*
X541346D01*
G01X498649Y159848D02*
X500307Y158190D01*
G01X476817Y159848D02*
X498649D01*
G01X495443Y155752D02*
X563036D01*
G01X469775Y130084D02*
X495443Y155752D01*
G01X461392Y130084D02*
X469775D01*
G01X474313Y164799D02*
X500700D01*
G01X552700Y108606D02*
Y124621D01*
G01X550197Y106103D02*
X552700Y108606D01*
G01X554664Y105058D02*
Y123012D01*
G01X550197Y100591D02*
X554664Y105058D01*
G01X540195Y105081D02*
Y123399D01*
G01X543110Y102166D02*
X540195Y105081D01*
G01X533515Y108612D02*
Y125607D01*
G01X536024Y106103D02*
X533515Y108612D01*
G01X550197Y114764D02*
X545781Y119180D01*
G01X552700Y124621D02*
X557788Y129709D01*
G01X538805Y163281D02*
X548232Y172708D01*
G01X554664Y123012D02*
X559367Y127715D01*
G01X551469Y134673D02*
X569029D01*
G01X540195Y123399D02*
X551469Y134673D01*
G01X541346Y158190D02*
X550543Y167387D01*
G01X550442Y136298D02*
X569703D01*
G01X542989Y128845D02*
X550442Y136298D01*
G01X536753Y128845D02*
X542989D01*
G01X533515Y125607D02*
X536753Y128845D01*
G01X552496Y133048D02*
X568253D01*
G01X545781Y126333D02*
X552496Y133048D01*
G01X545781Y119180D02*
Y126333D01*
G01X553523Y131423D02*
X567579D01*
G01X547785Y125685D02*
X553523Y131423D01*
G01X547785Y122688D02*
Y125685D01*
G01X550197Y120276D02*
X547785Y122688D01*
G01X548232Y172708D02*
X596763D01*
G01X550543Y167387D02*
X566271D01*
G01X515457Y1364700D02*
X510504Y1359747D01*
G01X788728Y1364700D02*
X515457D01*
G01X517600Y1362600D02*
X511522Y1356522D01*
G01X791228Y1362600D02*
X517600D01*
G01X566133Y129709D02*
X628567Y67275D01*
G01X565475Y127715D02*
X627540Y65650D01*
G01X569029Y134673D02*
X631552Y72150D01*
G01X593672Y112329D02*
X607929D01*
G01X569703Y136298D02*
X593672Y112329D01*
G01X568253Y133048D02*
X630776Y70525D01*
G01X567579Y131423D02*
X630102Y68900D01*
G01X557788Y129709D02*
X566133D01*
G01X559367Y127715D02*
X565475D01*
G01X568726Y161442D02*
X613723D01*
G01X563036Y155752D02*
X568726Y161442D01*
G01X603079Y166392D02*
X722692D01*
G01X596763Y172708D02*
X603079Y166392D01*
G01X628567Y67275D02*
X656480D01*
G01X627540Y65650D02*
X655736D01*
G01X631552Y72150D02*
X658572D01*
G01X646483Y73775D02*
X659246D01*
G01X607929Y112329D02*
X646483Y73775D01*
G01X630776Y70525D02*
X657898D01*
G01X630102Y68900D02*
X657224D01*
G01X613723Y161442D02*
X664252Y110913D01*
G01X656480Y67275D02*
X708233Y15522D01*
G01X655736Y65650D02*
X707489Y13897D01*
G01X658572Y72150D02*
X708035Y22687D01*
G01X659246Y73775D02*
X708284Y24737D01*
G01X657898Y70525D02*
X709323Y19100D01*
G01X657224Y68900D02*
X708977Y17147D01*
G01X685147Y110913D02*
X694093Y119859D01*
G01X664252Y110913D02*
X685147D01*
G01X694093Y119859D02*
X735015D01*
G01X708233Y15522D02*
X874859D01*
G01X707489Y13897D02*
X874185D01*
G01X708977Y17147D02*
X875533D01*
G01X708035Y22687D02*
X895975D01*
G01X708284Y24737D02*
X896396D01*
G01X709323Y19100D02*
X875879D01*
G01X735015Y119859D02*
X878038Y262882D01*
G01X728800Y172500D02*
X763188D01*
G01X722692Y166392D02*
X728800Y172500D01*
G01X785640Y1328949D02*
Y1328370D01*
G01X837800Y1381109D02*
X785640Y1328949D01*
G01X809991Y1385963D02*
X788728Y1364700D01*
G01X790290Y1328844D02*
Y1328410D01*
G01X840800Y1379354D02*
X790290Y1328844D01*
G01X813243Y1384615D02*
X791228Y1362600D01*
G01X837800Y1512163D02*
Y1381109D01*
G01X809991Y1550791D02*
Y1385963D01*
G01X840800Y1510920D02*
Y1379354D01*
G01X813243Y1549443D02*
Y1384615D01*
G01X842688Y1517051D02*
X837800Y1512163D01*
G01X842688Y1551289D02*
Y1517051D01*
G01X845688Y1515808D02*
X840800Y1510920D01*
G01X845688Y1550045D02*
Y1515808D01*
G01X872605Y1581206D02*
X842688Y1551289D01*
G01X844600Y1585400D02*
X809991Y1550791D01*
G01X878427Y1582784D02*
X845688Y1550045D01*
G01X851500Y1587700D02*
X813243Y1549443D01*
G01X844600Y1630000D02*
Y1585400D01*
G01X846884Y1632284D02*
X844600Y1630000D01*
G01X876378Y14003D02*
X896128D01*
G01X874859Y15522D02*
X876378Y14003D01*
G01X875704Y12378D02*
X895454D01*
G01X874185Y13897D02*
X875704Y12378D01*
G01X877487Y17492D02*
X898434D01*
G01X875879Y19100D02*
X877487Y17492D01*
G01X876813Y15867D02*
X897560D01*
G01X875533Y17147D02*
X876813Y15867D01*
G01X878038Y262882D02*
Y327670D01*
G01X890982Y340614D02*
Y349498D01*
G01X878038Y327670D02*
X890982Y340614D01*
G01X930343Y896320D02*
X882333D01*
G01X890420Y1562660D02*
X902100Y1550980D01*
G01X890420Y1567610D02*
Y1562660D01*
G01X892980Y1570170D02*
X890420Y1567610D01*
G01X892980Y1646760D02*
Y1570170D01*
G01X872605Y1608826D02*
Y1581206D01*
G01X876378Y1612599D02*
X872605Y1608826D01*
G01X894940Y1568450D02*
X893020Y1566530D01*
G01X878427Y1586999D02*
Y1582784D01*
G01X879400Y1587972D02*
X878427Y1586999D01*
G01X879400Y1616200D02*
Y1587972D01*
G01X851500Y1625400D02*
Y1587700D01*
G01X897008Y1650788D02*
X892980Y1646760D01*
G01X848032Y1632284D02*
X846884D01*
G01X877489Y1618111D02*
X879400Y1616200D01*
G01X876378Y1618111D02*
X877489D01*
G01X850128Y1626772D02*
X851500Y1625400D01*
G01X848032Y1626772D02*
X850128D01*
G01X923975Y-13844D02*
X947841D01*
G01X896128Y14003D02*
X923975Y-13844D01*
G01X923301Y-15469D02*
X948515D01*
G01X895454Y12378D02*
X923301Y-15469D01*
G01X927115Y-8453D02*
X928138D01*
G01X895975Y22687D02*
X927115Y-8453D01*
G01X922604Y176D02*
X922687Y93D01*
G01X920957Y176D02*
X922604D01*
G01X896396Y24737D02*
X920957Y176D01*
G01X926492Y-10566D02*
X946521D01*
G01X898434Y17492D02*
X926492Y-10566D01*
G01X925646Y-12219D02*
X947167D01*
G01X897560Y15867D02*
X925646Y-12219D01*
G01X934868Y900845D02*
X930343Y896320D01*
G01X941274Y900845D02*
X934868D01*
G01X940904Y971054D02*
X935623D01*
G01X948388Y978538D02*
X940904Y971054D01*
G01X931800Y977700D02*
X943900Y989800D01*
G01X931800Y971736D02*
Y977700D01*
G01X932482Y971054D02*
X931800Y971736D01*
G01X935623Y971054D02*
X932482D01*
G01X936378Y1028802D02*
Y1035722D01*
G01X946050Y1019130D02*
X936378Y1028802D01*
G01X921562Y1377037D02*
X982918D01*
G01X915487Y1383112D02*
X921562Y1377037D01*
G01X915487Y1482513D02*
Y1383112D01*
G01X925237Y1404582D02*
X944657Y1385162D01*
G01X925237Y1488463D02*
Y1404582D01*
G01X941638Y1378662D02*
X982244D01*
G01X917112Y1403188D02*
X941638Y1378662D01*
G01X917112Y1484288D02*
Y1403188D01*
G01X920888Y1375412D02*
X983592D01*
G01X913862Y1382438D02*
X920888Y1375412D01*
G01X913862Y1481839D02*
Y1382438D01*
G01X918737Y1404185D02*
X942635Y1380287D01*
G01X918737Y1485767D02*
Y1404185D01*
G01X942635Y1380287D02*
X981570D01*
G01X920362Y1404859D02*
X943309Y1381912D01*
G01X920362Y1486441D02*
Y1404859D01*
G01X923612Y1403908D02*
X943983Y1383537D01*
G01X923612Y1487789D02*
Y1403908D01*
G01X904062Y1493938D02*
X915487Y1482513D01*
G01X904062Y1557405D02*
Y1493938D01*
G01X916267Y1497433D02*
X925237Y1488463D01*
G01X916267Y1539731D02*
Y1497433D01*
G01X907083Y1494317D02*
X917112Y1484288D01*
G01X907083Y1542042D02*
Y1494317D01*
G01X902100Y1493601D02*
X913862Y1481839D01*
G01X902100Y1550980D02*
Y1493601D01*
G01X908708Y1495796D02*
X918737Y1485767D01*
G01X908708Y1541368D02*
Y1495796D01*
G01X910333Y1496470D02*
X920362Y1486441D01*
G01X910333Y1540694D02*
Y1496470D01*
G01X914642Y1496759D02*
X923612Y1487789D01*
G01X914642Y1540405D02*
Y1496759D01*
G01X918662Y1572005D02*
X904062Y1557405D01*
G01X918438Y1541902D02*
X916267Y1539731D01*
G01X918438Y1557183D02*
Y1541902D01*
G01X929777Y1568522D02*
X918438Y1557183D01*
G01X907938Y1542897D02*
X907083Y1542042D01*
G01X907938Y1558982D02*
Y1542897D01*
G01X920537Y1571581D02*
X907938Y1558982D01*
G01X909563Y1542223D02*
X908708Y1541368D01*
G01X909563Y1558308D02*
Y1542223D01*
G01X922621Y1571366D02*
X909563Y1558308D01*
G01X911188Y1541549D02*
X910333Y1540694D01*
G01X911188Y1556830D02*
Y1541549D01*
G01X924246Y1569888D02*
X911188Y1556830D01*
G01X916813Y1542576D02*
X914642Y1540405D01*
G01X916813Y1557857D02*
Y1542576D01*
G01X927603Y1568647D02*
X916813Y1557857D01*
G01X918662Y1619921D02*
Y1572005D01*
G01X929777Y1632822D02*
Y1568522D01*
G01X920537Y1623558D02*
Y1571581D01*
G01X902100Y1591985D02*
X911710Y1582375D01*
G01X902100Y1609580D02*
Y1591985D01*
G01X904725Y1612205D02*
X902100Y1609580D01*
G01X894940Y1634870D02*
Y1568450D01*
G01X922621Y1625804D02*
Y1571366D01*
G01X924246Y1628510D02*
Y1569888D01*
G01X927603Y1630665D02*
Y1568647D01*
G01X911094Y1589629D02*
Y1585923D01*
G01X907993Y1592730D02*
X911094Y1589629D01*
G01X907993Y1604606D02*
Y1592730D01*
G01X904725Y1607874D02*
X907993Y1604606D01*
G01X911811Y1626772D02*
X918662Y1619921D01*
G01X911811Y1650788D02*
X929777Y1632822D01*
G01X911811Y1632284D02*
X920537Y1623558D01*
G01X897638Y1650788D02*
X897008D01*
G01X896684Y1636614D02*
X894940Y1634870D01*
G01X897638Y1636614D02*
X896684D01*
G01X911811D02*
X922621Y1625804D01*
G01X911811Y1640945D02*
X924246Y1628510D01*
G01X911811Y1646457D02*
X927603Y1630665D01*
G01X957651Y-4034D02*
X1037606D01*
G01X947841Y-13844D02*
X957651Y-4034D01*
G01X958324Y-5660D02*
X1036730D01*
G01X948515Y-15469D02*
X958324Y-5660D01*
G01X956303Y-784D02*
X1038954D01*
G01X946521Y-10566D02*
X956303Y-784D01*
G01X956977Y-2409D02*
X1038280D01*
G01X947167Y-12219D02*
X956977Y-2409D01*
G01X986697Y978538D02*
X948388D01*
G01X987734Y979575D02*
X986697Y978538D01*
G01X946050Y1013490D02*
Y1019130D01*
G01X943900Y1011340D02*
X946050Y1013490D01*
G01X943900Y989800D02*
Y1011340D01*
G01X982918Y1377037D02*
X1013881Y1408000D01*
G01X977271Y1385162D02*
X1016109Y1424000D01*
G01X944657Y1385162D02*
X977271D01*
G01X982244Y1378662D02*
X1014582Y1411000D01*
G01X983592Y1375412D02*
X1009390Y1401210D01*
G01X981570Y1380287D02*
X1014876Y1413593D01*
G01X980896Y1381912D02*
X1015109Y1416125D01*
G01X943309Y1381912D02*
X980896D01*
G01X977945Y1383537D02*
X1016783Y1422375D01*
G01X943983Y1383537D02*
X977945D01*
G01X1037606Y-4034D02*
X1067935Y-34363D01*
G01X1036730Y-5660D02*
X1067277Y-36207D01*
G01X1038954Y-784D02*
X1068912Y-30742D01*
G01X1038280Y-2409D02*
X1068555Y-32684D01*
G01X1013881Y1408000D02*
X1031500D01*
G01X1014582Y1411000D02*
X1028000D01*
G01X1032810Y1401210D02*
X1049100Y1417500D01*
G01X1009390Y1401210D02*
X1032810D01*
G01X1014876Y1413593D02*
X1040093D01*
G01X1015109Y1416125D02*
X1033000D01*
G01X1016109Y1424000D02*
X1137450D01*
G01X1016783Y1422375D02*
X1136423D01*
G01X1081942Y-33461D02*
X1102872D01*
G01X1081040Y-34363D02*
X1081942Y-33461D01*
G01X1067935Y-34363D02*
X1081040D01*
G01X1082615Y-35087D02*
X1107187D01*
G01X1081495Y-36207D02*
X1082615Y-35087D01*
G01X1067277Y-36207D02*
X1081495D01*
G01X1068912Y-30742D02*
X1079455D01*
G01X1081268Y-31836D02*
X1100415D01*
G01X1080420Y-32684D02*
X1081268Y-31836D01*
G01X1068555Y-32684D02*
X1080420D01*
G01X1049100Y1417500D02*
X1133342D01*
G01X1045625Y1419125D02*
X1134369D01*
G01X1040093Y1413593D02*
X1045625Y1419125D01*
G01X1102872Y-33461D02*
X1105328Y-31005D01*
G01X1107187Y-35087D02*
X1111254Y-31020D01*
G01X1100415Y-31836D02*
X1101246Y-31005D01*
G01X1123700Y10700D02*
X1178007D01*
G01X1118100Y16300D02*
X1123700Y10700D01*
G01X1109016Y16300D02*
X1118100D01*
G01X1105315Y12599D02*
X1109016Y16300D01*
G01X1133342Y1417500D02*
X1146375Y1404467D01*
G01X1134369Y1419125D02*
X1148000Y1405494D01*
G01X1178007Y10700D02*
X1239907Y72600D01*
G01X1149166Y1234030D02*
X1149823Y1233373D01*
G01X1149166Y1304536D02*
Y1234030D01*
G01X1151761Y1231141D02*
X1150420Y1229800D01*
G01X1151761Y1304240D02*
Y1231141D01*
G01X1146375Y1307327D02*
X1149166Y1304536D01*
G01X1146375Y1404467D02*
Y1307327D01*
G01X1148000Y1308001D02*
X1151761Y1304240D01*
G01X1148000Y1405494D02*
Y1308001D01*
G01X1152936Y1329064D02*
X1154500Y1327500D01*
G01X1152936Y1408514D02*
Y1329064D01*
G01X1150911Y1407887D02*
Y1329500D01*
G01X1137450Y1424000D02*
X1152936Y1408514D01*
G01X1136423Y1422375D02*
X1150911Y1407887D01*
G01X1239907Y72600D02*
X1319200D01*
G01X1328295Y63505D02*
Y55800D01*
G01X1319200Y72600D02*
X1328295Y63505D01*
M02*
